FILE_TYPE = MACRO_DRAWING;
SET COLOR_WIRE YELLOW;
SET COLOR_PROP ORANGE;
SET COLOR_DOT WHITE;
SET COLOR_ARC YELLOW;
SET COLOR_BODY GREEN;
SET COLOR_NOTE PURPLE;
SET PROP_DISPLAY VALUE;
SET PAGE_NUMBER P212;
FORCEADD HOLE..1
(-8725 4225);
FORCEPROP 1 LAST LOCATION H76
J 0
(-8850 4460);
DISPLAY 0.723404 (-8850 4460);
PAINT GREEN (-8850 4460);
FORCEPROP 0 LAST $SEC 1
J 0
(-8850 4550);
DISPLAY 0.680851 (-8850 4550);
PAINT MONO (-8850 4550);
DISPLAY INVISIBLE (-8850 4550);
FORCEPROP 0 LAST CDS_SEC 1
J 0
(-8850 4550);
DISPLAY 1.021277 (-8850 4550);
DISPLAY INVISIBLE (-8850 4550);
FORCEPROP 0 LASTPIN (-8925 4250) $PN 1
J 2
(-8935 4260);
DISPLAY 0.680851 (-8935 4260);
PAINT MONO (-8935 4260);
FORCEPROP 1 LAST MATERIAL EMPTY
J 0
(-8850 4360);
DISPLAY 0.723404 (-8850 4360);
PAINT GREEN (-8850 4360);
FORCEPROP 2 LAST PACK_TYPE TH
J 0
(-8850 4500);
DISPLAY 1.021277 (-8850 4500);
FORCEPROP 1 LAST NEEDS_NO_SIZE TRUE
J 0
(-8725 4225);
DISPLAY 0.468085 (-8725 4225);
PAINT GREEN (-8725 4225);
DISPLAY INVISIBLE (-8725 4225);
FORCEPROP 2 LAST CDS_LIB pure_quanta
J 0
(-8725 4225);
DISPLAY INVISIBLE (-8725 4225);
FORCEPROP 1 LAST PATH I10
J 0
(-8675 4355);
DISPLAY 0.723404 (-8675 4355);
PAINT GREEN (-8675 4355);
DISPLAY INVISIBLE (-8675 4355);
FORCEPROP 1 LAST PART_NUMBER HOLE1187
J 0
(-8850 4405);
DISPLAY 0.723404 (-8850 4405);
PAINT GREEN (-8850 4405);
DISPLAY INVISIBLE (-8850 4405);
FORCEADD CONN1_10165288101LF..1
(-1650 5400);
FORCEPROP 1 LAST LOCATION J122
J 0
(-1700 5625);
DISPLAY 0.723404 (-1700 5625);
PAINT GREEN (-1700 5625);
FORCEPROP 0 LAST $SEC 1
J 0
(-1675 5950);
DISPLAY 0.680851 (-1675 5950);
PAINT MONO (-1675 5950);
DISPLAY INVISIBLE (-1675 5950);
FORCEPROP 0 LAST CDS_SEC 1
J 0
(-1675 5950);
DISPLAY 1.021277 (-1675 5950);
DISPLAY INVISIBLE (-1675 5950);
FORCEPROP 0 LASTPIN (-1450 5375) $PN SCR_H1
J 0
(-1440 5385);
DISPLAY 0.680851 (-1440 5385);
PAINT MONO (-1440 5385);
FORCEPROP 2 LAST VALUE CONN1_10165288-101LF
J 0
(-1700 5675);
DISPLAY 0.808511 (-1700 5675);
FORCEPROP 2 LAST PART_TYPE THLF
J 0
(-1700 5750);
DISPLAY 0.808511 (-1700 5750);
FORCEPROP 1 LAST MATERIAL IO
J 0
(-1694 5532);
DISPLAY 0.723404 (-1694 5532);
PAINT GREEN (-1694 5532);
FORCEPROP 2 LAST CDS_LIB pure_quanta
J 0
(-1650 5400);
DISPLAY INVISIBLE (-1650 5400);
FORCEPROP 1 LAST NEEDS_NO_SIZE TRUE
J 0
(-1650 5400);
DISPLAY 0.723404 (-1650 5400);
PAINT GREEN (-1650 5400);
DISPLAY INVISIBLE (-1650 5400);
FORCEPROP 1 LAST CDS_LMAN_SYM_OUTLINE -50,125,50,-125
J 0
(-1650 5400);
DISPLAY 0.468085 (-1650 5400);
PAINT GREEN (-1650 5400);
DISPLAY INVISIBLE (-1650 5400);
FORCEPROP 1 LAST PATH I101
J 0
(-1650 5400);
DISPLAY 0.723404 (-1650 5400);
PAINT GREEN (-1650 5400);
DISPLAY INVISIBLE (-1650 5400);
FORCEPROP 1 LAST PART_NUMBER DFHS03FR030
J 0
(-1700 5575);
DISPLAY 0.723404 (-1700 5575);
PAINT GREEN (-1700 5575);
DISPLAY INVISIBLE (-1700 5575);
FORCEADD CONN1_10165288101LF..1
(-825 5400);
FORCEPROP 1 LAST LOCATION J123
J 0
(-875 5625);
DISPLAY 0.723404 (-875 5625);
PAINT GREEN (-875 5625);
FORCEPROP 0 LAST $SEC 1
J 0
(-850 5950);
DISPLAY 0.680851 (-850 5950);
PAINT MONO (-850 5950);
DISPLAY INVISIBLE (-850 5950);
FORCEPROP 0 LAST CDS_SEC 1
J 0
(-850 5950);
DISPLAY 1.021277 (-850 5950);
DISPLAY INVISIBLE (-850 5950);
FORCEPROP 0 LASTPIN (-625 5375) $PN SCR_H1
J 0
(-615 5385);
DISPLAY 0.680851 (-615 5385);
PAINT MONO (-615 5385);
FORCEPROP 1 LAST MATERIAL IO
J 0
(-869 5532);
DISPLAY 0.723404 (-869 5532);
PAINT GREEN (-869 5532);
FORCEPROP 2 LAST VALUE CONN1_10165288-101LF
J 0
(-875 5675);
DISPLAY 0.808511 (-875 5675);
FORCEPROP 2 LAST PART_TYPE THLF
J 0
(-875 5725);
DISPLAY 0.808511 (-875 5725);
FORCEPROP 1 LAST NEEDS_NO_SIZE TRUE
J 0
(-825 5400);
DISPLAY 0.723404 (-825 5400);
PAINT GREEN (-825 5400);
DISPLAY INVISIBLE (-825 5400);
FORCEPROP 1 LAST CDS_LMAN_SYM_OUTLINE -50,125,50,-125
J 0
(-825 5400);
DISPLAY 0.468085 (-825 5400);
PAINT GREEN (-825 5400);
DISPLAY INVISIBLE (-825 5400);
FORCEPROP 2 LAST CDS_LIB pure_quanta
J 0
(-825 5400);
DISPLAY INVISIBLE (-825 5400);
FORCEPROP 1 LAST PATH I106
J 0
(-825 5400);
DISPLAY 0.723404 (-825 5400);
PAINT GREEN (-825 5400);
DISPLAY INVISIBLE (-825 5400);
FORCEPROP 1 LAST PART_NUMBER DFHS03FR030
J 0
(-875 5575);
DISPLAY 0.723404 (-875 5575);
PAINT GREEN (-875 5575);
DISPLAY INVISIBLE (-875 5575);
FORCEADD UNIVERSAL_GND..1
(-8450 4075);
FORCEPROP 3 LASTPIN (-8450 4125) SIG_NAME GND\g
J 0
(-8440 4135);
DISPLAY 0.659574 (-8440 4135);
PAINT MONO (-8440 4135);
DISPLAY INVISIBLE (-8440 4135);
FORCEPROP 2 LAST CDS_LIB pure_quanta_power
J 0
(-8450 4075);
DISPLAY INVISIBLE (-8450 4075);
FORCEPROP 1 LAST HDL_POWER GND
J 1
(-8425 4000);
DISPLAY 0.872340 (-8425 4000);
PAINT GREEN (-8425 4000);
DISPLAY INVISIBLE (-8425 4000);
FORCEPROP 1 LAST PATH I11
J 0
(-8375 4075);
DISPLAY 0.872340 (-8375 4075);
PAINT AQUA (-8375 4075);
DISPLAY INVISIBLE (-8375 4075);
FORCEADD HOLE..1
(-2875 475);
FORCEPROP 1 LAST LOCATION H126
J 0
(-3000 710);
DISPLAY 0.723404 (-3000 710);
PAINT GREEN (-3000 710);
FORCEPROP 0 LAST $SEC 1
J 0
(-3000 800);
DISPLAY 0.680851 (-3000 800);
PAINT MONO (-3000 800);
DISPLAY INVISIBLE (-3000 800);
FORCEPROP 0 LAST CDS_SEC 1
J 0
(-3000 800);
DISPLAY 1.021277 (-3000 800);
DISPLAY INVISIBLE (-3000 800);
FORCEPROP 0 LASTPIN (-3075 500) $PN 1
J 2
(-3085 510);
DISPLAY 0.680851 (-3085 510);
PAINT MONO (-3085 510);
FORCEPROP 1 LAST MATERIAL EMPTY
J 0
(-3000 610);
DISPLAY 0.723404 (-3000 610);
PAINT GREEN (-3000 610);
FORCEPROP 2 LAST PACK_TYPE TH
J 0
(-3000 750);
DISPLAY 1.021277 (-3000 750);
FORCEPROP 2 LAST CDS_LIB pure_quanta
J 0
(-2875 475);
DISPLAY INVISIBLE (-2875 475);
FORCEPROP 1 LAST NEEDS_NO_SIZE TRUE
J 0
(-2875 475);
DISPLAY 0.468085 (-2875 475);
PAINT GREEN (-2875 475);
DISPLAY INVISIBLE (-2875 475);
FORCEPROP 1 LAST PATH I111
J 0
(-2825 605);
DISPLAY 0.723404 (-2825 605);
PAINT GREEN (-2825 605);
DISPLAY INVISIBLE (-2825 605);
FORCEPROP 1 LAST PART_NUMBER TMP-C_T2I_ALEX_1121_1
J 0
(-3000 655);
DISPLAY 0.723404 (-3000 655);
PAINT GREEN (-3000 655);
DISPLAY INVISIBLE (-3000 655);
FORCEADD HOLE..1
(-825 1400);
FORCEPROP 1 LAST LOCATION H6000
J 0
(-950 1635);
DISPLAY 0.489362 (-950 1635);
PAINT SKYBLUE (-950 1635);
FORCEPROP 0 LAST $SEC 1
J 0
(-950 1700);
DISPLAY 0.680851 (-950 1700);
PAINT MONO (-950 1700);
DISPLAY INVISIBLE (-950 1700);
FORCEPROP 0 LAST CDS_SEC 1
J 0
(-950 1700);
DISPLAY 0.680851 (-950 1700);
DISPLAY INVISIBLE (-950 1700);
FORCEPROP 0 LASTPIN (-1025 1425) $PN 1
J 2
(-1035 1435);
DISPLAY 0.680851 (-1035 1435);
PAINT MONO (-1035 1435);
FORCEPROP 2 LAST PACK_TYPE TH
J 0
(-950 1675);
DISPLAY 0.489362 (-950 1675);
PAINT SKYBLUE (-950 1675);
FORCEPROP 1 LAST MATERIAL EMPTY
J 0
(-950 1535);
DISPLAY 0.489362 (-950 1535);
PAINT RED (-950 1535);
FORCEPROP 2 LAST CDS_LIB pure_quanta
J 0
(-825 1400);
DISPLAY INVISIBLE (-825 1400);
FORCEPROP 1 LAST NEEDS_NO_SIZE TRUE
J 0
(-825 1400);
DISPLAY 0.468085 (-825 1400);
PAINT GREEN (-825 1400);
DISPLAY INVISIBLE (-825 1400);
FORCEPROP 1 LAST PATH I113
J 0
(-775 1530);
DISPLAY 0.723404 (-775 1530);
PAINT GREEN (-775 1530);
DISPLAY INVISIBLE (-775 1530);
FORCEPROP 1 LAST PART_NUMBER HOLE1226
J 0
(-950 1580);
DISPLAY 0.489362 (-950 1580);
PAINT SKYBLUE (-950 1580);
DISPLAY INVISIBLE (-950 1580);
FORCEADD UNIVERSAL_GND..1
(-1025 1325);
FORCEPROP 3 LASTPIN (-1025 1375) SIG_NAME GND\g
J 0
(-1015 1385);
DISPLAY 0.659574 (-1015 1385);
PAINT MONO (-1015 1385);
DISPLAY INVISIBLE (-1015 1385);
FORCEPROP 2 LAST CDS_LIB pure_quanta_power
J 0
(-1025 1325);
DISPLAY INVISIBLE (-1025 1325);
FORCEPROP 1 LAST HDL_POWER GND
J 1
(-1000 1250);
DISPLAY 0.872340 (-1000 1250);
PAINT GREEN (-1000 1250);
DISPLAY INVISIBLE (-1000 1250);
FORCEPROP 1 LAST PATH I114
J 0
(-950 1325);
DISPLAY 0.872340 (-950 1325);
PAINT AQUA (-950 1325);
DISPLAY INVISIBLE (-950 1325);
FORCEADD UNIVERSAL_GND..1
(-500 1300);
FORCEPROP 3 LASTPIN (-500 1350) SIG_NAME GND\g
J 0
(-490 1360);
DISPLAY 0.659574 (-490 1360);
PAINT MONO (-490 1360);
DISPLAY INVISIBLE (-490 1360);
FORCEPROP 2 LAST CDS_LIB pure_quanta_power
J 0
(-500 1300);
DISPLAY INVISIBLE (-500 1300);
FORCEPROP 1 LAST HDL_POWER GND
J 1
(-475 1225);
DISPLAY 0.872340 (-475 1225);
PAINT GREEN (-475 1225);
DISPLAY INVISIBLE (-475 1225);
FORCEPROP 1 LAST PATH I115
J 0
(-425 1300);
DISPLAY 0.872340 (-425 1300);
PAINT AQUA (-425 1300);
DISPLAY INVISIBLE (-425 1300);
FORCEADD HOLE..1
(-300 1375);
FORCEPROP 1 LAST LOCATION H6001
J 0
(-425 1610);
DISPLAY 0.489362 (-425 1610);
PAINT SKYBLUE (-425 1610);
FORCEPROP 0 LAST $SEC 1
J 0
(-425 1675);
DISPLAY 0.680851 (-425 1675);
PAINT MONO (-425 1675);
DISPLAY INVISIBLE (-425 1675);
FORCEPROP 0 LAST CDS_SEC 1
J 0
(-425 1675);
DISPLAY 0.680851 (-425 1675);
DISPLAY INVISIBLE (-425 1675);
FORCEPROP 0 LASTPIN (-500 1400) $PN 1
J 2
(-510 1410);
DISPLAY 0.680851 (-510 1410);
PAINT MONO (-510 1410);
FORCEPROP 1 LAST MATERIAL EMPTY
J 0
(-425 1510);
DISPLAY 0.489362 (-425 1510);
PAINT RED (-425 1510);
FORCEPROP 2 LAST PACK_TYPE TH
J 0
(-425 1650);
DISPLAY 0.489362 (-425 1650);
PAINT SKYBLUE (-425 1650);
FORCEPROP 1 LAST NEEDS_NO_SIZE TRUE
J 0
(-300 1375);
DISPLAY 0.468085 (-300 1375);
PAINT GREEN (-300 1375);
DISPLAY INVISIBLE (-300 1375);
FORCEPROP 2 LAST CDS_LIB pure_quanta
J 0
(-300 1375);
DISPLAY INVISIBLE (-300 1375);
FORCEPROP 1 LAST PATH I116
J 0
(-250 1505);
DISPLAY 0.723404 (-250 1505);
PAINT GREEN (-250 1505);
DISPLAY INVISIBLE (-250 1505);
FORCEPROP 1 LAST PART_NUMBER HOLE1226
J 0
(-425 1555);
DISPLAY 0.489362 (-425 1555);
PAINT SKYBLUE (-425 1555);
DISPLAY INVISIBLE (-425 1555);
FORCEADD HOLE..1
(-8175 4225);
FORCEPROP 1 LAST LOCATION H77
J 0
(-8300 4460);
DISPLAY 0.723404 (-8300 4460);
PAINT GREEN (-8300 4460);
FORCEPROP 0 LAST $SEC 1
J 0
(-8300 4550);
DISPLAY 0.680851 (-8300 4550);
PAINT MONO (-8300 4550);
DISPLAY INVISIBLE (-8300 4550);
FORCEPROP 0 LAST CDS_SEC 1
J 0
(-8300 4550);
DISPLAY 1.021277 (-8300 4550);
DISPLAY INVISIBLE (-8300 4550);
FORCEPROP 0 LASTPIN (-8375 4250) $PN 1
J 2
(-8385 4260);
DISPLAY 0.680851 (-8385 4260);
PAINT MONO (-8385 4260);
FORCEPROP 1 LAST MATERIAL EMPTY
J 0
(-8300 4360);
DISPLAY 0.723404 (-8300 4360);
PAINT GREEN (-8300 4360);
FORCEPROP 2 LAST PACK_TYPE TH
J 0
(-8300 4500);
DISPLAY 1.021277 (-8300 4500);
FORCEPROP 1 LAST NEEDS_NO_SIZE TRUE
J 0
(-8175 4225);
DISPLAY 0.468085 (-8175 4225);
PAINT GREEN (-8175 4225);
DISPLAY INVISIBLE (-8175 4225);
FORCEPROP 2 LAST CDS_LIB pure_quanta
J 0
(-8175 4225);
DISPLAY INVISIBLE (-8175 4225);
FORCEPROP 1 LAST PATH I12
J 0
(-8125 4355);
DISPLAY 0.723404 (-8125 4355);
PAINT GREEN (-8125 4355);
DISPLAY INVISIBLE (-8125 4355);
FORCEPROP 1 LAST PART_NUMBER HOLE1187
J 0
(-8300 4405);
DISPLAY 0.723404 (-8300 4405);
PAINT GREEN (-8300 4405);
DISPLAY INVISIBLE (-8300 4405);
FORCEADD GND_HOLE..1
(-7225 800);
FORCEPROP 1 LAST LOCATION H111
J 0
(-7375 1225);
DISPLAY 0.723404 (-7375 1225);
PAINT GREEN (-7375 1225);
FORCEPROP 2 LAST SEC 1
J 0
(-7375 1325);
DISPLAY 0.680851 (-7375 1325);
PAINT MONO (-7375 1325);
DISPLAY INVISIBLE (-7375 1325);
FORCEPROP 2 LASTPIN (-7025 800) $PN 2
J 0
(-7015 810);
DISPLAY 0.680851 (-7015 810);
PAINT MONO (-7015 810);
FORCEPROP 2 LASTPIN (-7025 900) $PN 3
J 0
(-7015 910);
DISPLAY 0.680851 (-7015 910);
PAINT MONO (-7015 910);
FORCEPROP 2 LASTPIN (-7225 1000) $PN 4
R 1
J 0
(-7235 1010);
DISPLAY 0.680851 (-7235 1010);
PAINT MONO (-7235 1010);
FORCEPROP 2 LASTPIN (-7425 900) $PN 5
J 2
(-7435 910);
DISPLAY 0.680851 (-7435 910);
PAINT MONO (-7435 910);
FORCEPROP 2 LASTPIN (-7425 800) $PN 6
J 2
(-7435 810);
DISPLAY 0.680851 (-7435 810);
PAINT MONO (-7435 810);
FORCEPROP 2 LASTPIN (-7325 600) $PN 7
R 1
J 2
(-7335 590);
DISPLAY 0.680851 (-7335 590);
PAINT MONO (-7335 590);
FORCEPROP 2 LASTPIN (-7225 600) $PN 8
R 1
J 2
(-7235 590);
DISPLAY 0.680851 (-7235 590);
PAINT MONO (-7235 590);
FORCEPROP 2 LASTPIN (-7125 600) $PN 9
R 1
J 2
(-7135 590);
DISPLAY 0.680851 (-7135 590);
PAINT MONO (-7135 590);
FORCEPROP 2 LAST PACK_TYPE TH
J 0
(-7375 1275);
DISPLAY 0.680851 (-7375 1275);
FORCEPROP 1 LAST MATERIAL EMPTY
J 0
(-7375 1130);
DISPLAY 0.723404 (-7375 1130);
PAINT GREEN (-7375 1130);
FORCEPROP 2 LAST SEC_TYPE TH
J 0
(-7375 1325);
DISPLAY 0.680851 (-7375 1325);
DISPLAY INVISIBLE (-7375 1325);
FORCEPROP 2 LAST CDS_LIB pure_quanta
J 0
(-7225 800);
DISPLAY INVISIBLE (-7225 800);
FORCEPROP 1 LAST NEEDS_NO_SIZE TRUE
J 0
(-7225 800);
DISPLAY 0.468085 (-7225 800);
PAINT GREEN (-7225 800);
DISPLAY INVISIBLE (-7225 800);
FORCEPROP 1 LAST PATH I120
J 0
(-7125 1110);
DISPLAY 0.723404 (-7125 1110);
PAINT GREEN (-7125 1110);
DISPLAY INVISIBLE (-7125 1110);
FORCEPROP 1 LAST PART_NUMBER TMP-QGND_HOLE12
J 0
(-7375 1185);
DISPLAY 0.723404 (-7375 1185);
PAINT GREEN (-7375 1185);
DISPLAY INVISIBLE (-7375 1185);
FORCEADD UNIVERSAL_GND..1
(-7500 400);
FORCEPROP 3 LASTPIN (-7500 450) SIG_NAME GND\g
J 0
(-7490 460);
DISPLAY 0.659574 (-7490 460);
PAINT MONO (-7490 460);
DISPLAY INVISIBLE (-7490 460);
FORCEPROP 2 LAST CDS_LIB pure_quanta_power
J 0
(-7500 400);
DISPLAY INVISIBLE (-7500 400);
FORCEPROP 1 LAST HDL_POWER GND
J 1
(-7475 325);
DISPLAY 0.872340 (-7475 325);
PAINT GREEN (-7475 325);
DISPLAY INVISIBLE (-7475 325);
FORCEPROP 1 LAST PATH I122
J 0
(-7425 400);
DISPLAY 0.872340 (-7425 400);
PAINT AQUA (-7425 400);
DISPLAY INVISIBLE (-7425 400);
FORCEADD GND_HOLE..1
(-6475 825);
FORCEPROP 1 LAST LOCATION H112
J 0
(-6625 1250);
DISPLAY 0.723404 (-6625 1250);
PAINT GREEN (-6625 1250);
FORCEPROP 2 LAST SEC 1
J 0
(-6625 1350);
DISPLAY 0.680851 (-6625 1350);
PAINT MONO (-6625 1350);
DISPLAY INVISIBLE (-6625 1350);
FORCEPROP 2 LASTPIN (-6275 825) $PN 2
J 0
(-6265 835);
DISPLAY 0.680851 (-6265 835);
PAINT MONO (-6265 835);
FORCEPROP 2 LASTPIN (-6275 925) $PN 3
J 0
(-6265 935);
DISPLAY 0.680851 (-6265 935);
PAINT MONO (-6265 935);
FORCEPROP 2 LASTPIN (-6475 1025) $PN 4
R 1
J 0
(-6485 1035);
DISPLAY 0.680851 (-6485 1035);
PAINT MONO (-6485 1035);
FORCEPROP 2 LASTPIN (-6675 925) $PN 5
J 2
(-6685 935);
DISPLAY 0.680851 (-6685 935);
PAINT MONO (-6685 935);
FORCEPROP 2 LASTPIN (-6675 825) $PN 6
J 2
(-6685 835);
DISPLAY 0.680851 (-6685 835);
PAINT MONO (-6685 835);
FORCEPROP 2 LASTPIN (-6575 625) $PN 7
R 1
J 2
(-6585 615);
DISPLAY 0.680851 (-6585 615);
PAINT MONO (-6585 615);
FORCEPROP 2 LASTPIN (-6475 625) $PN 8
R 1
J 2
(-6485 615);
DISPLAY 0.680851 (-6485 615);
PAINT MONO (-6485 615);
FORCEPROP 2 LASTPIN (-6375 625) $PN 9
R 1
J 2
(-6385 615);
DISPLAY 0.680851 (-6385 615);
PAINT MONO (-6385 615);
FORCEPROP 1 LAST MATERIAL EMPTY
J 0
(-6625 1155);
DISPLAY 0.723404 (-6625 1155);
PAINT GREEN (-6625 1155);
FORCEPROP 2 LAST PACK_TYPE TH
J 0
(-6625 1300);
DISPLAY 0.680851 (-6625 1300);
FORCEPROP 2 LAST SEC_TYPE TH
J 0
(-6625 1350);
DISPLAY 0.680851 (-6625 1350);
DISPLAY INVISIBLE (-6625 1350);
FORCEPROP 2 LAST CDS_LIB pure_quanta
J 0
(-6475 825);
DISPLAY INVISIBLE (-6475 825);
FORCEPROP 1 LAST NEEDS_NO_SIZE TRUE
J 0
(-6475 825);
DISPLAY 0.468085 (-6475 825);
PAINT GREEN (-6475 825);
DISPLAY INVISIBLE (-6475 825);
FORCEPROP 1 LAST PATH I123
J 0
(-6375 1135);
DISPLAY 0.723404 (-6375 1135);
PAINT GREEN (-6375 1135);
DISPLAY INVISIBLE (-6375 1135);
FORCEPROP 1 LAST PART_NUMBER TMP-QGND_HOLE12
J 0
(-6625 1210);
DISPLAY 0.723404 (-6625 1210);
PAINT GREEN (-6625 1210);
DISPLAY INVISIBLE (-6625 1210);
FORCEADD UNIVERSAL_GND..1
(-6750 425);
FORCEPROP 3 LASTPIN (-6750 475) SIG_NAME GND\g
J 0
(-6740 485);
DISPLAY 0.659574 (-6740 485);
PAINT MONO (-6740 485);
DISPLAY INVISIBLE (-6740 485);
FORCEPROP 2 LAST CDS_LIB pure_quanta_power
J 0
(-6750 425);
DISPLAY INVISIBLE (-6750 425);
FORCEPROP 1 LAST HDL_POWER GND
J 1
(-6725 350);
DISPLAY 0.872340 (-6725 350);
PAINT GREEN (-6725 350);
DISPLAY INVISIBLE (-6725 350);
FORCEPROP 1 LAST PATH I124
J 0
(-6675 425);
DISPLAY 0.872340 (-6675 425);
PAINT AQUA (-6675 425);
DISPLAY INVISIBLE (-6675 425);
FORCEADD HOLE..1
(-8800 5875);
FORCEPROP 1 LAST LOCATION H86
J 0
(-8925 6110);
DISPLAY 0.723404 (-8925 6110);
PAINT GREEN (-8925 6110);
FORCEPROP 0 LAST $SEC 1
J 0
(-8925 6200);
DISPLAY 0.680851 (-8925 6200);
PAINT MONO (-8925 6200);
DISPLAY INVISIBLE (-8925 6200);
FORCEPROP 0 LAST CDS_SEC 1
J 0
(-8925 6200);
DISPLAY 0.680851 (-8925 6200);
DISPLAY INVISIBLE (-8925 6200);
FORCEPROP 0 LASTPIN (-9000 5900) $PN 1
J 2
(-9010 5910);
DISPLAY 0.680851 (-9010 5910);
PAINT MONO (-9010 5910);
FORCEPROP 2 LAST PACK_TYPE TH
J 0
(-8925 6150);
DISPLAY 0.680851 (-8925 6150);
FORCEPROP 1 LAST MATERIAL EMPTY
J 0
(-8925 6010);
DISPLAY 0.723404 (-8925 6010);
PAINT GREEN (-8925 6010);
FORCEPROP 2 LAST CDS_LIB pure_quanta
J 0
(-8800 5875);
DISPLAY INVISIBLE (-8800 5875);
FORCEPROP 1 LAST NEEDS_NO_SIZE TRUE
J 0
(-8800 5875);
DISPLAY 0.468085 (-8800 5875);
PAINT GREEN (-8800 5875);
DISPLAY INVISIBLE (-8800 5875);
FORCEPROP 1 LAST PATH I125
J 0
(-8750 6005);
DISPLAY 0.723404 (-8750 6005);
PAINT GREEN (-8750 6005);
DISPLAY INVISIBLE (-8750 6005);
FORCEPROP 1 LAST PART_NUMBER HOLE596
J 0
(-8925 6055);
DISPLAY 0.723404 (-8925 6055);
PAINT GREEN (-8925 6055);
DISPLAY INVISIBLE (-8925 6055);
FORCEADD UNIVERSAL_GND..1
(-9100 5750);
FORCEPROP 3 LASTPIN (-9100 5800) SIG_NAME GND\g
J 0
(-9090 5810);
DISPLAY 0.659574 (-9090 5810);
PAINT MONO (-9090 5810);
DISPLAY INVISIBLE (-9090 5810);
FORCEPROP 2 LAST CDS_LIB pure_quanta_power
J 0
(-9100 5750);
DISPLAY INVISIBLE (-9100 5750);
FORCEPROP 1 LAST HDL_POWER GND
J 1
(-9075 5675);
DISPLAY 0.872340 (-9075 5675);
PAINT GREEN (-9075 5675);
DISPLAY INVISIBLE (-9075 5675);
FORCEPROP 1 LAST PATH I126
J 0
(-9025 5750);
DISPLAY 0.872340 (-9025 5750);
PAINT AQUA (-9025 5750);
DISPLAY INVISIBLE (-9025 5750);
FORCEADD HOLE..1
(-8775 5325);
FORCEPROP 1 LAST LOCATION H87
J 0
(-8900 5560);
DISPLAY 0.723404 (-8900 5560);
PAINT GREEN (-8900 5560);
FORCEPROP 0 LAST $SEC 1
J 0
(-8900 5650);
DISPLAY 0.680851 (-8900 5650);
PAINT MONO (-8900 5650);
DISPLAY INVISIBLE (-8900 5650);
FORCEPROP 0 LAST CDS_SEC 1
J 0
(-8900 5650);
DISPLAY 0.680851 (-8900 5650);
DISPLAY INVISIBLE (-8900 5650);
FORCEPROP 0 LASTPIN (-8975 5350) $PN 1
J 2
(-8985 5360);
DISPLAY 0.680851 (-8985 5360);
PAINT MONO (-8985 5360);
FORCEPROP 2 LAST PACK_TYPE TH
J 0
(-8900 5600);
DISPLAY 0.680851 (-8900 5600);
FORCEPROP 1 LAST MATERIAL EMPTY
J 0
(-8900 5460);
DISPLAY 0.723404 (-8900 5460);
PAINT GREEN (-8900 5460);
FORCEPROP 2 LAST CDS_LIB pure_quanta
J 0
(-8775 5325);
DISPLAY INVISIBLE (-8775 5325);
FORCEPROP 1 LAST NEEDS_NO_SIZE TRUE
J 0
(-8775 5325);
DISPLAY 0.468085 (-8775 5325);
PAINT GREEN (-8775 5325);
DISPLAY INVISIBLE (-8775 5325);
FORCEPROP 1 LAST PATH I127
J 0
(-8725 5455);
DISPLAY 0.723404 (-8725 5455);
PAINT GREEN (-8725 5455);
DISPLAY INVISIBLE (-8725 5455);
FORCEPROP 1 LAST PART_NUMBER HOLE596
J 0
(-8900 5505);
DISPLAY 0.723404 (-8900 5505);
PAINT GREEN (-8900 5505);
DISPLAY INVISIBLE (-8900 5505);
FORCEADD UNIVERSAL_GND..1
(-9050 5225);
FORCEPROP 3 LASTPIN (-9050 5275) SIG_NAME GND\g
J 0
(-9040 5285);
DISPLAY 0.659574 (-9040 5285);
PAINT MONO (-9040 5285);
DISPLAY INVISIBLE (-9040 5285);
FORCEPROP 2 LAST CDS_LIB pure_quanta_power
J 0
(-9050 5225);
DISPLAY INVISIBLE (-9050 5225);
FORCEPROP 1 LAST HDL_POWER GND
J 1
(-9025 5150);
DISPLAY 0.872340 (-9025 5150);
PAINT GREEN (-9025 5150);
DISPLAY INVISIBLE (-9025 5150);
FORCEPROP 1 LAST PATH I128
J 0
(-8975 5225);
DISPLAY 0.872340 (-8975 5225);
PAINT AQUA (-8975 5225);
DISPLAY INVISIBLE (-8975 5225);
FORCEADD HOLE..1
(-8175 5900);
FORCEPROP 1 LAST LOCATION H88
J 0
(-8300 6135);
DISPLAY 0.723404 (-8300 6135);
PAINT GREEN (-8300 6135);
FORCEPROP 0 LAST $SEC 1
J 0
(-8300 6225);
DISPLAY 0.680851 (-8300 6225);
PAINT MONO (-8300 6225);
DISPLAY INVISIBLE (-8300 6225);
FORCEPROP 0 LAST CDS_SEC 1
J 0
(-8300 6225);
DISPLAY 0.680851 (-8300 6225);
DISPLAY INVISIBLE (-8300 6225);
FORCEPROP 0 LASTPIN (-8375 5925) $PN 1
J 2
(-8385 5935);
DISPLAY 0.680851 (-8385 5935);
PAINT MONO (-8385 5935);
FORCEPROP 1 LAST MATERIAL EMPTY
J 0
(-8300 6035);
DISPLAY 0.723404 (-8300 6035);
PAINT GREEN (-8300 6035);
FORCEPROP 2 LAST PACK_TYPE TH
J 0
(-8300 6175);
DISPLAY 0.680851 (-8300 6175);
FORCEPROP 1 LAST NEEDS_NO_SIZE TRUE
J 0
(-8175 5900);
DISPLAY 0.468085 (-8175 5900);
PAINT GREEN (-8175 5900);
DISPLAY INVISIBLE (-8175 5900);
FORCEPROP 2 LAST CDS_LIB pure_quanta
J 0
(-8175 5900);
DISPLAY INVISIBLE (-8175 5900);
FORCEPROP 1 LAST PATH I129
J 0
(-8125 6030);
DISPLAY 0.723404 (-8125 6030);
PAINT GREEN (-8125 6030);
DISPLAY INVISIBLE (-8125 6030);
FORCEPROP 1 LAST PART_NUMBER HOLE596
J 0
(-8300 6080);
DISPLAY 0.723404 (-8300 6080);
PAINT GREEN (-8300 6080);
DISPLAY INVISIBLE (-8300 6080);
FORCEADD UNIVERSAL_GND..1
(-8475 5800);
FORCEPROP 3 LASTPIN (-8475 5850) SIG_NAME GND\g
J 0
(-8465 5860);
DISPLAY 0.659574 (-8465 5860);
PAINT MONO (-8465 5860);
DISPLAY INVISIBLE (-8465 5860);
FORCEPROP 2 LAST CDS_LIB pure_quanta_power
J 0
(-8475 5800);
DISPLAY INVISIBLE (-8475 5800);
FORCEPROP 1 LAST HDL_POWER GND
J 1
(-8450 5725);
DISPLAY 0.872340 (-8450 5725);
PAINT GREEN (-8450 5725);
DISPLAY INVISIBLE (-8450 5725);
FORCEPROP 1 LAST PATH I130
J 0
(-8400 5800);
DISPLAY 0.872340 (-8400 5800);
PAINT AQUA (-8400 5800);
DISPLAY INVISIBLE (-8400 5800);
FORCEADD UNIVERSAL_GND..1
(-8425 5225);
FORCEPROP 3 LASTPIN (-8425 5275) SIG_NAME GND\g
J 0
(-8415 5285);
DISPLAY 0.659574 (-8415 5285);
PAINT MONO (-8415 5285);
DISPLAY INVISIBLE (-8415 5285);
FORCEPROP 2 LAST CDS_LIB pure_quanta_power
J 0
(-8425 5225);
DISPLAY INVISIBLE (-8425 5225);
FORCEPROP 1 LAST HDL_POWER GND
J 1
(-8400 5150);
DISPLAY 0.872340 (-8400 5150);
PAINT GREEN (-8400 5150);
DISPLAY INVISIBLE (-8400 5150);
FORCEPROP 1 LAST PATH I131
J 0
(-8350 5225);
DISPLAY 0.872340 (-8350 5225);
PAINT AQUA (-8350 5225);
DISPLAY INVISIBLE (-8350 5225);
FORCEADD HOLE..1
(-8150 5325);
FORCEPROP 1 LAST LOCATION H89
J 0
(-8275 5560);
DISPLAY 0.723404 (-8275 5560);
PAINT GREEN (-8275 5560);
FORCEPROP 0 LAST $SEC 1
J 0
(-8275 5650);
DISPLAY 0.680851 (-8275 5650);
PAINT MONO (-8275 5650);
DISPLAY INVISIBLE (-8275 5650);
FORCEPROP 0 LAST CDS_SEC 1
J 0
(-8275 5650);
DISPLAY 0.680851 (-8275 5650);
DISPLAY INVISIBLE (-8275 5650);
FORCEPROP 0 LASTPIN (-8350 5350) $PN 1
J 2
(-8360 5360);
DISPLAY 0.680851 (-8360 5360);
PAINT MONO (-8360 5360);
FORCEPROP 1 LAST MATERIAL EMPTY
J 0
(-8275 5460);
DISPLAY 0.723404 (-8275 5460);
PAINT GREEN (-8275 5460);
FORCEPROP 2 LAST PACK_TYPE TH
J 0
(-8275 5600);
DISPLAY 0.680851 (-8275 5600);
FORCEPROP 1 LAST NEEDS_NO_SIZE TRUE
J 0
(-8150 5325);
DISPLAY 0.468085 (-8150 5325);
PAINT GREEN (-8150 5325);
DISPLAY INVISIBLE (-8150 5325);
FORCEPROP 2 LAST CDS_LIB pure_quanta
J 0
(-8150 5325);
DISPLAY INVISIBLE (-8150 5325);
FORCEPROP 1 LAST PATH I132
J 0
(-8100 5455);
DISPLAY 0.723404 (-8100 5455);
PAINT GREEN (-8100 5455);
DISPLAY INVISIBLE (-8100 5455);
FORCEPROP 1 LAST PART_NUMBER HOLE596
J 0
(-8275 5505);
DISPLAY 0.723404 (-8275 5505);
PAINT GREEN (-8275 5505);
DISPLAY INVISIBLE (-8275 5505);
FORCEADD HOLE..1
(-7475 5900);
FORCEPROP 1 LAST LOCATION H91
J 0
(-7600 6135);
DISPLAY 0.723404 (-7600 6135);
PAINT GREEN (-7600 6135);
FORCEPROP 0 LAST $SEC 1
J 0
(-7600 6225);
DISPLAY 0.680851 (-7600 6225);
PAINT MONO (-7600 6225);
DISPLAY INVISIBLE (-7600 6225);
FORCEPROP 0 LAST CDS_SEC 1
J 0
(-7600 6225);
DISPLAY 0.680851 (-7600 6225);
DISPLAY INVISIBLE (-7600 6225);
FORCEPROP 0 LASTPIN (-7675 5925) $PN 1
J 2
(-7685 5935);
DISPLAY 0.680851 (-7685 5935);
PAINT MONO (-7685 5935);
FORCEPROP 2 LAST PACK_TYPE TH
J 0
(-7600 6175);
DISPLAY 0.680851 (-7600 6175);
FORCEPROP 1 LAST MATERIAL EMPTY
J 0
(-7600 6035);
DISPLAY 0.723404 (-7600 6035);
PAINT GREEN (-7600 6035);
FORCEPROP 1 LAST NEEDS_NO_SIZE TRUE
J 0
(-7475 5900);
DISPLAY 0.468085 (-7475 5900);
PAINT GREEN (-7475 5900);
DISPLAY INVISIBLE (-7475 5900);
FORCEPROP 2 LAST CDS_LIB pure_quanta
J 0
(-7475 5900);
DISPLAY INVISIBLE (-7475 5900);
FORCEPROP 1 LAST PATH I133
J 0
(-7425 6030);
DISPLAY 0.723404 (-7425 6030);
PAINT GREEN (-7425 6030);
DISPLAY INVISIBLE (-7425 6030);
FORCEPROP 1 LAST PART_NUMBER HOLE596
J 0
(-7600 6080);
DISPLAY 0.723404 (-7600 6080);
PAINT GREEN (-7600 6080);
DISPLAY INVISIBLE (-7600 6080);
FORCEADD UNIVERSAL_GND..1
(-7775 5825);
FORCEPROP 3 LASTPIN (-7775 5875) SIG_NAME GND\g
J 0
(-7765 5885);
DISPLAY 0.659574 (-7765 5885);
PAINT MONO (-7765 5885);
DISPLAY INVISIBLE (-7765 5885);
FORCEPROP 2 LAST CDS_LIB pure_quanta_power
J 0
(-7775 5825);
DISPLAY INVISIBLE (-7775 5825);
FORCEPROP 1 LAST HDL_POWER GND
J 1
(-7750 5750);
DISPLAY 0.872340 (-7750 5750);
PAINT GREEN (-7750 5750);
DISPLAY INVISIBLE (-7750 5750);
FORCEPROP 1 LAST PATH I134
J 0
(-7700 5825);
DISPLAY 0.872340 (-7700 5825);
PAINT AQUA (-7700 5825);
DISPLAY INVISIBLE (-7700 5825);
FORCEADD HOLE..1
(-7475 5350);
FORCEPROP 1 LAST LOCATION H92
J 0
(-7600 5585);
DISPLAY 0.723404 (-7600 5585);
PAINT GREEN (-7600 5585);
FORCEPROP 0 LAST $SEC 1
J 0
(-7600 5675);
DISPLAY 0.680851 (-7600 5675);
PAINT MONO (-7600 5675);
DISPLAY INVISIBLE (-7600 5675);
FORCEPROP 0 LAST CDS_SEC 1
J 0
(-7600 5675);
DISPLAY 0.680851 (-7600 5675);
DISPLAY INVISIBLE (-7600 5675);
FORCEPROP 0 LASTPIN (-7675 5375) $PN 1
J 2
(-7685 5385);
DISPLAY 0.680851 (-7685 5385);
PAINT MONO (-7685 5385);
FORCEPROP 1 LAST MATERIAL EMPTY
J 0
(-7600 5485);
DISPLAY 0.723404 (-7600 5485);
PAINT GREEN (-7600 5485);
FORCEPROP 2 LAST PACK_TYPE TH
J 0
(-7600 5625);
DISPLAY 0.680851 (-7600 5625);
FORCEPROP 2 LAST CDS_LIB pure_quanta
J 0
(-7475 5350);
DISPLAY INVISIBLE (-7475 5350);
FORCEPROP 1 LAST NEEDS_NO_SIZE TRUE
J 0
(-7475 5350);
DISPLAY 0.468085 (-7475 5350);
PAINT GREEN (-7475 5350);
DISPLAY INVISIBLE (-7475 5350);
FORCEPROP 1 LAST PATH I135
J 0
(-7425 5480);
DISPLAY 0.723404 (-7425 5480);
PAINT GREEN (-7425 5480);
DISPLAY INVISIBLE (-7425 5480);
FORCEPROP 1 LAST PART_NUMBER HOLE596
J 0
(-7600 5530);
DISPLAY 0.723404 (-7600 5530);
PAINT GREEN (-7600 5530);
DISPLAY INVISIBLE (-7600 5530);
FORCEADD UNIVERSAL_GND..1
(-7750 5250);
FORCEPROP 3 LASTPIN (-7750 5300) SIG_NAME GND\g
J 0
(-7740 5310);
DISPLAY 0.659574 (-7740 5310);
PAINT MONO (-7740 5310);
DISPLAY INVISIBLE (-7740 5310);
FORCEPROP 2 LAST CDS_LIB pure_quanta_power
J 0
(-7750 5250);
DISPLAY INVISIBLE (-7750 5250);
FORCEPROP 1 LAST HDL_POWER GND
J 1
(-7725 5175);
DISPLAY 0.872340 (-7725 5175);
PAINT GREEN (-7725 5175);
DISPLAY INVISIBLE (-7725 5175);
FORCEPROP 1 LAST PATH I136
J 0
(-7675 5250);
DISPLAY 0.872340 (-7675 5250);
PAINT AQUA (-7675 5250);
DISPLAY INVISIBLE (-7675 5250);
FORCEADD UNIVERSAL_GND..1
(-7125 5850);
FORCEPROP 3 LASTPIN (-7125 5900) SIG_NAME GND\g
J 0
(-7115 5910);
DISPLAY 0.659574 (-7115 5910);
PAINT MONO (-7115 5910);
DISPLAY INVISIBLE (-7115 5910);
FORCEPROP 2 LAST CDS_LIB pure_quanta_power
J 0
(-7125 5850);
DISPLAY INVISIBLE (-7125 5850);
FORCEPROP 1 LAST HDL_POWER GND
J 1
(-7100 5775);
DISPLAY 0.872340 (-7100 5775);
PAINT GREEN (-7100 5775);
DISPLAY INVISIBLE (-7100 5775);
FORCEPROP 1 LAST PATH I137
J 0
(-7050 5850);
DISPLAY 0.872340 (-7050 5850);
PAINT AQUA (-7050 5850);
DISPLAY INVISIBLE (-7050 5850);
FORCEADD HOLE..1
(-6850 5900);
FORCEPROP 1 LAST LOCATION H93
J 0
(-6975 6135);
DISPLAY 0.723404 (-6975 6135);
PAINT GREEN (-6975 6135);
FORCEPROP 0 LAST $SEC 1
J 0
(-6975 6225);
DISPLAY 0.680851 (-6975 6225);
PAINT MONO (-6975 6225);
DISPLAY INVISIBLE (-6975 6225);
FORCEPROP 0 LAST CDS_SEC 1
J 0
(-6975 6225);
DISPLAY 0.680851 (-6975 6225);
DISPLAY INVISIBLE (-6975 6225);
FORCEPROP 0 LASTPIN (-7050 5925) $PN 1
J 2
(-7060 5935);
DISPLAY 0.680851 (-7060 5935);
PAINT MONO (-7060 5935);
FORCEPROP 1 LAST MATERIAL EMPTY
J 0
(-6975 6035);
DISPLAY 0.723404 (-6975 6035);
PAINT GREEN (-6975 6035);
FORCEPROP 2 LAST PACK_TYPE TH
J 0
(-6975 6175);
DISPLAY 0.680851 (-6975 6175);
FORCEPROP 2 LAST CDS_LIB pure_quanta
J 0
(-6850 5900);
DISPLAY INVISIBLE (-6850 5900);
FORCEPROP 1 LAST NEEDS_NO_SIZE TRUE
J 0
(-6850 5900);
DISPLAY 0.468085 (-6850 5900);
PAINT GREEN (-6850 5900);
DISPLAY INVISIBLE (-6850 5900);
FORCEPROP 1 LAST PATH I138
J 0
(-6800 6030);
DISPLAY 0.723404 (-6800 6030);
PAINT GREEN (-6800 6030);
DISPLAY INVISIBLE (-6800 6030);
FORCEPROP 1 LAST PART_NUMBER HOLE596
J 0
(-6975 6080);
DISPLAY 0.723404 (-6975 6080);
PAINT GREEN (-6975 6080);
DISPLAY INVISIBLE (-6975 6080);
FORCEADD UNIVERSAL_GND..1
(-7050 5250);
FORCEPROP 3 LASTPIN (-7050 5300) SIG_NAME GND\g
J 0
(-7040 5310);
DISPLAY 0.659574 (-7040 5310);
PAINT MONO (-7040 5310);
DISPLAY INVISIBLE (-7040 5310);
FORCEPROP 2 LAST CDS_LIB pure_quanta_power
J 0
(-7050 5250);
DISPLAY INVISIBLE (-7050 5250);
FORCEPROP 1 LAST HDL_POWER GND
J 1
(-7025 5175);
DISPLAY 0.872340 (-7025 5175);
PAINT GREEN (-7025 5175);
DISPLAY INVISIBLE (-7025 5175);
FORCEPROP 1 LAST PATH I139
J 0
(-6975 5250);
DISPLAY 0.872340 (-6975 5250);
PAINT AQUA (-6975 5250);
DISPLAY INVISIBLE (-6975 5250);
FORCEADD HOLE..1
(-6800 5325);
FORCEPROP 1 LAST LOCATION H94
J 0
(-6925 5560);
DISPLAY 0.723404 (-6925 5560);
PAINT GREEN (-6925 5560);
FORCEPROP 0 LAST $SEC 1
J 0
(-6925 5650);
DISPLAY 0.680851 (-6925 5650);
PAINT MONO (-6925 5650);
DISPLAY INVISIBLE (-6925 5650);
FORCEPROP 0 LAST CDS_SEC 1
J 0
(-6925 5650);
DISPLAY 0.680851 (-6925 5650);
DISPLAY INVISIBLE (-6925 5650);
FORCEPROP 0 LASTPIN (-7000 5350) $PN 1
J 2
(-7010 5360);
DISPLAY 0.680851 (-7010 5360);
PAINT MONO (-7010 5360);
FORCEPROP 1 LAST MATERIAL EMPTY
J 0
(-6925 5460);
DISPLAY 0.723404 (-6925 5460);
PAINT GREEN (-6925 5460);
FORCEPROP 2 LAST PACK_TYPE TH
J 0
(-6925 5600);
DISPLAY 0.680851 (-6925 5600);
FORCEPROP 2 LAST CDS_LIB pure_quanta
J 0
(-6800 5325);
DISPLAY INVISIBLE (-6800 5325);
FORCEPROP 1 LAST NEEDS_NO_SIZE TRUE
J 0
(-6800 5325);
DISPLAY 0.468085 (-6800 5325);
PAINT GREEN (-6800 5325);
DISPLAY INVISIBLE (-6800 5325);
FORCEPROP 1 LAST PATH I140
J 0
(-6750 5455);
DISPLAY 0.723404 (-6750 5455);
PAINT GREEN (-6750 5455);
DISPLAY INVISIBLE (-6750 5455);
FORCEPROP 1 LAST PART_NUMBER HOLE596
J 0
(-6925 5505);
DISPLAY 0.723404 (-6925 5505);
PAINT GREEN (-6925 5505);
DISPLAY INVISIBLE (-6925 5505);
FORCEADD HOLE..1
(-6200 5875);
FORCEPROP 1 LAST LOCATION H95
J 0
(-6325 6110);
DISPLAY 0.723404 (-6325 6110);
PAINT GREEN (-6325 6110);
FORCEPROP 0 LAST $SEC 1
J 0
(-6325 6200);
DISPLAY 0.680851 (-6325 6200);
PAINT MONO (-6325 6200);
DISPLAY INVISIBLE (-6325 6200);
FORCEPROP 0 LAST CDS_SEC 1
J 0
(-6325 6200);
DISPLAY 0.680851 (-6325 6200);
DISPLAY INVISIBLE (-6325 6200);
FORCEPROP 0 LASTPIN (-6400 5900) $PN 1
J 2
(-6410 5910);
DISPLAY 0.680851 (-6410 5910);
PAINT MONO (-6410 5910);
FORCEPROP 2 LAST PACK_TYPE TH
J 0
(-6325 6150);
DISPLAY 0.680851 (-6325 6150);
FORCEPROP 1 LAST MATERIAL EMPTY
J 0
(-6325 6010);
DISPLAY 0.723404 (-6325 6010);
PAINT GREEN (-6325 6010);
FORCEPROP 2 LAST CDS_LIB pure_quanta
J 0
(-6200 5875);
DISPLAY INVISIBLE (-6200 5875);
FORCEPROP 1 LAST NEEDS_NO_SIZE TRUE
J 0
(-6200 5875);
DISPLAY 0.468085 (-6200 5875);
PAINT GREEN (-6200 5875);
DISPLAY INVISIBLE (-6200 5875);
FORCEPROP 1 LAST PATH I141
J 0
(-6150 6005);
DISPLAY 0.723404 (-6150 6005);
PAINT GREEN (-6150 6005);
DISPLAY INVISIBLE (-6150 6005);
FORCEPROP 1 LAST PART_NUMBER HOLE596
J 0
(-6325 6055);
DISPLAY 0.723404 (-6325 6055);
PAINT GREEN (-6325 6055);
DISPLAY INVISIBLE (-6325 6055);
FORCEADD HOLE..1
(-6150 5350);
FORCEPROP 1 LAST LOCATION H96
J 0
(-6275 5585);
DISPLAY 0.723404 (-6275 5585);
PAINT GREEN (-6275 5585);
FORCEPROP 0 LAST $SEC 1
J 0
(-6275 5675);
DISPLAY 0.680851 (-6275 5675);
PAINT MONO (-6275 5675);
DISPLAY INVISIBLE (-6275 5675);
FORCEPROP 0 LAST CDS_SEC 1
J 0
(-6275 5675);
DISPLAY 0.680851 (-6275 5675);
DISPLAY INVISIBLE (-6275 5675);
FORCEPROP 0 LASTPIN (-6350 5375) $PN 1
J 2
(-6360 5385);
DISPLAY 0.680851 (-6360 5385);
PAINT MONO (-6360 5385);
FORCEPROP 1 LAST MATERIAL EMPTY
J 0
(-6275 5485);
DISPLAY 0.723404 (-6275 5485);
PAINT GREEN (-6275 5485);
FORCEPROP 2 LAST PACK_TYPE TH
J 0
(-6275 5625);
DISPLAY 0.680851 (-6275 5625);
FORCEPROP 2 LAST CDS_LIB pure_quanta
J 0
(-6150 5350);
DISPLAY INVISIBLE (-6150 5350);
FORCEPROP 1 LAST NEEDS_NO_SIZE TRUE
J 0
(-6150 5350);
DISPLAY 0.468085 (-6150 5350);
PAINT GREEN (-6150 5350);
DISPLAY INVISIBLE (-6150 5350);
FORCEPROP 1 LAST PATH I142
J 0
(-6100 5480);
DISPLAY 0.723404 (-6100 5480);
PAINT GREEN (-6100 5480);
DISPLAY INVISIBLE (-6100 5480);
FORCEPROP 1 LAST PART_NUMBER HOLE596
J 0
(-6275 5530);
DISPLAY 0.723404 (-6275 5530);
PAINT GREEN (-6275 5530);
DISPLAY INVISIBLE (-6275 5530);
FORCEADD UNIVERSAL_GND..1
(-6400 5300);
FORCEPROP 3 LASTPIN (-6400 5350) SIG_NAME GND\g
J 0
(-6390 5360);
DISPLAY 0.659574 (-6390 5360);
PAINT MONO (-6390 5360);
DISPLAY INVISIBLE (-6390 5360);
FORCEPROP 2 LAST CDS_LIB pure_quanta_power
J 0
(-6400 5300);
DISPLAY INVISIBLE (-6400 5300);
FORCEPROP 1 LAST HDL_POWER GND
J 1
(-6375 5225);
DISPLAY 0.872340 (-6375 5225);
PAINT GREEN (-6375 5225);
DISPLAY INVISIBLE (-6375 5225);
FORCEPROP 1 LAST PATH I143
J 0
(-6325 5300);
DISPLAY 0.872340 (-6325 5300);
PAINT AQUA (-6325 5300);
DISPLAY INVISIBLE (-6325 5300);
FORCEADD UNIVERSAL_GND..1
(-6450 5825);
FORCEPROP 3 LASTPIN (-6450 5875) SIG_NAME GND\g
J 0
(-6440 5885);
DISPLAY 0.659574 (-6440 5885);
PAINT MONO (-6440 5885);
DISPLAY INVISIBLE (-6440 5885);
FORCEPROP 2 LAST CDS_LIB pure_quanta_power
J 0
(-6450 5825);
DISPLAY INVISIBLE (-6450 5825);
FORCEPROP 1 LAST HDL_POWER GND
J 1
(-6425 5750);
DISPLAY 0.872340 (-6425 5750);
PAINT GREEN (-6425 5750);
DISPLAY INVISIBLE (-6425 5750);
FORCEPROP 1 LAST PATH I144
J 0
(-6375 5825);
DISPLAY 0.872340 (-6375 5825);
PAINT AQUA (-6375 5825);
DISPLAY INVISIBLE (-6375 5825);
FORCEADD HOLE..1
(-5475 5925);
FORCEPROP 1 LAST LOCATION H97
J 0
(-5600 6160);
DISPLAY 0.723404 (-5600 6160);
PAINT GREEN (-5600 6160);
FORCEPROP 0 LAST $SEC 1
J 0
(-5600 6250);
DISPLAY 0.680851 (-5600 6250);
PAINT MONO (-5600 6250);
DISPLAY INVISIBLE (-5600 6250);
FORCEPROP 0 LAST CDS_SEC 1
J 0
(-5600 6250);
DISPLAY 0.680851 (-5600 6250);
DISPLAY INVISIBLE (-5600 6250);
FORCEPROP 0 LASTPIN (-5675 5950) $PN 1
J 2
(-5685 5960);
DISPLAY 0.680851 (-5685 5960);
PAINT MONO (-5685 5960);
FORCEPROP 2 LAST PACK_TYPE TH
J 0
(-5600 6200);
DISPLAY 0.680851 (-5600 6200);
FORCEPROP 1 LAST MATERIAL EMPTY
J 0
(-5600 6060);
DISPLAY 0.723404 (-5600 6060);
PAINT GREEN (-5600 6060);
FORCEPROP 2 LAST CDS_LIB pure_quanta
J 0
(-5475 5925);
DISPLAY INVISIBLE (-5475 5925);
FORCEPROP 1 LAST NEEDS_NO_SIZE TRUE
J 0
(-5475 5925);
DISPLAY 0.468085 (-5475 5925);
PAINT GREEN (-5475 5925);
DISPLAY INVISIBLE (-5475 5925);
FORCEPROP 1 LAST PATH I145
J 0
(-5425 6055);
DISPLAY 0.723404 (-5425 6055);
PAINT GREEN (-5425 6055);
DISPLAY INVISIBLE (-5425 6055);
FORCEPROP 1 LAST PART_NUMBER HOLE596
J 0
(-5600 6105);
DISPLAY 0.723404 (-5600 6105);
PAINT GREEN (-5600 6105);
DISPLAY INVISIBLE (-5600 6105);
FORCEADD UNIVERSAL_GND..1
(-5725 5850);
FORCEPROP 3 LASTPIN (-5725 5900) SIG_NAME GND\g
J 0
(-5715 5910);
DISPLAY 0.659574 (-5715 5910);
PAINT MONO (-5715 5910);
DISPLAY INVISIBLE (-5715 5910);
FORCEPROP 2 LAST CDS_LIB pure_quanta_power
J 0
(-5725 5850);
DISPLAY INVISIBLE (-5725 5850);
FORCEPROP 1 LAST HDL_POWER GND
J 1
(-5700 5775);
DISPLAY 0.872340 (-5700 5775);
PAINT GREEN (-5700 5775);
DISPLAY INVISIBLE (-5700 5775);
FORCEPROP 1 LAST PATH I146
J 0
(-5650 5850);
DISPLAY 0.872340 (-5650 5850);
PAINT AQUA (-5650 5850);
DISPLAY INVISIBLE (-5650 5850);
FORCEADD HOLE..1
(-5450 5300);
FORCEPROP 1 LAST LOCATION H98
J 0
(-5575 5535);
DISPLAY 0.723404 (-5575 5535);
PAINT GREEN (-5575 5535);
FORCEPROP 0 LAST $SEC 1
J 0
(-5575 5625);
DISPLAY 0.680851 (-5575 5625);
PAINT MONO (-5575 5625);
DISPLAY INVISIBLE (-5575 5625);
FORCEPROP 0 LAST CDS_SEC 1
J 0
(-5575 5625);
DISPLAY 0.680851 (-5575 5625);
DISPLAY INVISIBLE (-5575 5625);
FORCEPROP 0 LASTPIN (-5650 5325) $PN 1
J 2
(-5660 5335);
DISPLAY 0.680851 (-5660 5335);
PAINT MONO (-5660 5335);
FORCEPROP 1 LAST MATERIAL EMPTY
J 0
(-5575 5435);
DISPLAY 0.723404 (-5575 5435);
PAINT GREEN (-5575 5435);
FORCEPROP 2 LAST PACK_TYPE TH
J 0
(-5575 5575);
DISPLAY 0.680851 (-5575 5575);
FORCEPROP 1 LAST NEEDS_NO_SIZE TRUE
J 0
(-5450 5300);
DISPLAY 0.468085 (-5450 5300);
PAINT GREEN (-5450 5300);
DISPLAY INVISIBLE (-5450 5300);
FORCEPROP 2 LAST CDS_LIB pure_quanta
J 0
(-5450 5300);
DISPLAY INVISIBLE (-5450 5300);
FORCEPROP 1 LAST PATH I147
J 0
(-5400 5430);
DISPLAY 0.723404 (-5400 5430);
PAINT GREEN (-5400 5430);
DISPLAY INVISIBLE (-5400 5430);
FORCEPROP 1 LAST PART_NUMBER HOLE596
J 0
(-5575 5480);
DISPLAY 0.723404 (-5575 5480);
PAINT GREEN (-5575 5480);
DISPLAY INVISIBLE (-5575 5480);
FORCEADD UNIVERSAL_GND..1
(-5700 5200);
FORCEPROP 3 LASTPIN (-5700 5250) SIG_NAME GND\g
J 0
(-5690 5260);
DISPLAY 0.659574 (-5690 5260);
PAINT MONO (-5690 5260);
DISPLAY INVISIBLE (-5690 5260);
FORCEPROP 2 LAST CDS_LIB pure_quanta_power
J 0
(-5700 5200);
DISPLAY INVISIBLE (-5700 5200);
FORCEPROP 1 LAST HDL_POWER GND
J 1
(-5675 5125);
DISPLAY 0.872340 (-5675 5125);
PAINT GREEN (-5675 5125);
DISPLAY INVISIBLE (-5675 5125);
FORCEPROP 1 LAST PATH I148
J 0
(-5625 5200);
DISPLAY 0.872340 (-5625 5200);
PAINT AQUA (-5625 5200);
DISPLAY INVISIBLE (-5625 5200);
FORCEADD HOLE..1
(-4750 5925);
FORCEPROP 1 LAST LOCATION H99
J 0
(-4875 6160);
DISPLAY 0.723404 (-4875 6160);
PAINT GREEN (-4875 6160);
FORCEPROP 0 LAST $SEC 1
J 0
(-4875 6250);
DISPLAY 0.680851 (-4875 6250);
PAINT MONO (-4875 6250);
DISPLAY INVISIBLE (-4875 6250);
FORCEPROP 0 LAST CDS_SEC 1
J 0
(-4875 6250);
DISPLAY 0.680851 (-4875 6250);
DISPLAY INVISIBLE (-4875 6250);
FORCEPROP 0 LASTPIN (-4950 5950) $PN 1
J 2
(-4960 5960);
DISPLAY 0.680851 (-4960 5960);
PAINT MONO (-4960 5960);
FORCEPROP 1 LAST MATERIAL EMPTY
J 0
(-4875 6060);
DISPLAY 0.723404 (-4875 6060);
PAINT GREEN (-4875 6060);
FORCEPROP 2 LAST PACK_TYPE TH
J 0
(-4875 6200);
DISPLAY 0.680851 (-4875 6200);
FORCEPROP 1 LAST NEEDS_NO_SIZE TRUE
J 0
(-4750 5925);
DISPLAY 0.468085 (-4750 5925);
PAINT GREEN (-4750 5925);
DISPLAY INVISIBLE (-4750 5925);
FORCEPROP 2 LAST CDS_LIB pure_quanta
J 0
(-4750 5925);
DISPLAY INVISIBLE (-4750 5925);
FORCEPROP 1 LAST PATH I149
J 0
(-4700 6055);
DISPLAY 0.723404 (-4700 6055);
PAINT GREEN (-4700 6055);
DISPLAY INVISIBLE (-4700 6055);
FORCEPROP 1 LAST PART_NUMBER HOLE596
J 0
(-4875 6105);
DISPLAY 0.723404 (-4875 6105);
PAINT GREEN (-4875 6105);
DISPLAY INVISIBLE (-4875 6105);
FORCEADD UNIVERSAL_GND..1
(-5025 5850);
FORCEPROP 3 LASTPIN (-5025 5900) SIG_NAME GND\g
J 0
(-5015 5910);
DISPLAY 0.659574 (-5015 5910);
PAINT MONO (-5015 5910);
DISPLAY INVISIBLE (-5015 5910);
FORCEPROP 2 LAST CDS_LIB pure_quanta_power
J 0
(-5025 5850);
DISPLAY INVISIBLE (-5025 5850);
FORCEPROP 1 LAST HDL_POWER GND
J 1
(-5000 5775);
DISPLAY 0.872340 (-5000 5775);
PAINT GREEN (-5000 5775);
DISPLAY INVISIBLE (-5000 5775);
FORCEPROP 1 LAST PATH I150
J 0
(-4950 5850);
DISPLAY 0.872340 (-4950 5850);
PAINT AQUA (-4950 5850);
DISPLAY INVISIBLE (-4950 5850);
FORCEADD UNIVERSAL_GND..1
(-5000 5200);
FORCEPROP 3 LASTPIN (-5000 5250) SIG_NAME GND\g
J 0
(-4990 5260);
DISPLAY 0.659574 (-4990 5260);
PAINT MONO (-4990 5260);
DISPLAY INVISIBLE (-4990 5260);
FORCEPROP 2 LAST CDS_LIB pure_quanta_power
J 0
(-5000 5200);
DISPLAY INVISIBLE (-5000 5200);
FORCEPROP 1 LAST HDL_POWER GND
J 1
(-4975 5125);
DISPLAY 0.872340 (-4975 5125);
PAINT GREEN (-4975 5125);
DISPLAY INVISIBLE (-4975 5125);
FORCEPROP 1 LAST PATH I151
J 0
(-4925 5200);
DISPLAY 0.872340 (-4925 5200);
PAINT AQUA (-4925 5200);
DISPLAY INVISIBLE (-4925 5200);
FORCEADD HOLE..1
(-4725 5300);
FORCEPROP 1 LAST LOCATION H100
J 0
(-4850 5535);
DISPLAY 0.723404 (-4850 5535);
PAINT GREEN (-4850 5535);
FORCEPROP 0 LAST $SEC 1
J 0
(-4850 5625);
DISPLAY 0.680851 (-4850 5625);
PAINT MONO (-4850 5625);
DISPLAY INVISIBLE (-4850 5625);
FORCEPROP 0 LAST CDS_SEC 1
J 0
(-4850 5625);
DISPLAY 0.680851 (-4850 5625);
DISPLAY INVISIBLE (-4850 5625);
FORCEPROP 0 LASTPIN (-4925 5325) $PN 1
J 2
(-4935 5335);
DISPLAY 0.680851 (-4935 5335);
PAINT MONO (-4935 5335);
FORCEPROP 2 LAST PACK_TYPE TH
J 0
(-4850 5575);
DISPLAY 0.680851 (-4850 5575);
FORCEPROP 1 LAST MATERIAL EMPTY
J 0
(-4850 5435);
DISPLAY 0.723404 (-4850 5435);
PAINT GREEN (-4850 5435);
FORCEPROP 2 LAST CDS_LIB pure_quanta
J 0
(-4725 5300);
DISPLAY INVISIBLE (-4725 5300);
FORCEPROP 1 LAST NEEDS_NO_SIZE TRUE
J 0
(-4725 5300);
DISPLAY 0.468085 (-4725 5300);
PAINT GREEN (-4725 5300);
DISPLAY INVISIBLE (-4725 5300);
FORCEPROP 1 LAST PATH I152
J 0
(-4675 5430);
DISPLAY 0.723404 (-4675 5430);
PAINT GREEN (-4675 5430);
DISPLAY INVISIBLE (-4675 5430);
FORCEPROP 1 LAST PART_NUMBER HOLE596
J 0
(-4850 5480);
DISPLAY 0.723404 (-4850 5480);
PAINT GREEN (-4850 5480);
DISPLAY INVISIBLE (-4850 5480);
FORCEADD HOLE..1
(-4100 5925);
FORCEPROP 1 LAST LOCATION H101
J 0
(-4225 6160);
DISPLAY 0.723404 (-4225 6160);
PAINT GREEN (-4225 6160);
FORCEPROP 0 LAST $SEC 1
J 0
(-4225 6250);
DISPLAY 0.680851 (-4225 6250);
PAINT MONO (-4225 6250);
DISPLAY INVISIBLE (-4225 6250);
FORCEPROP 0 LAST CDS_SEC 1
J 0
(-4225 6250);
DISPLAY 0.680851 (-4225 6250);
DISPLAY INVISIBLE (-4225 6250);
FORCEPROP 0 LASTPIN (-4300 5950) $PN 1
J 2
(-4310 5960);
DISPLAY 0.680851 (-4310 5960);
PAINT MONO (-4310 5960);
FORCEPROP 2 LAST PACK_TYPE TH
J 0
(-4225 6200);
DISPLAY 0.680851 (-4225 6200);
FORCEPROP 1 LAST MATERIAL EMPTY
J 0
(-4225 6060);
DISPLAY 0.723404 (-4225 6060);
PAINT GREEN (-4225 6060);
FORCEPROP 2 LAST CDS_LIB pure_quanta
J 0
(-4100 5925);
DISPLAY INVISIBLE (-4100 5925);
FORCEPROP 1 LAST NEEDS_NO_SIZE TRUE
J 0
(-4100 5925);
DISPLAY 0.468085 (-4100 5925);
PAINT GREEN (-4100 5925);
DISPLAY INVISIBLE (-4100 5925);
FORCEPROP 1 LAST PATH I153
J 0
(-4050 6055);
DISPLAY 0.723404 (-4050 6055);
PAINT GREEN (-4050 6055);
DISPLAY INVISIBLE (-4050 6055);
FORCEPROP 1 LAST PART_NUMBER HOLE596
J 0
(-4225 6105);
DISPLAY 0.723404 (-4225 6105);
PAINT GREEN (-4225 6105);
DISPLAY INVISIBLE (-4225 6105);
FORCEADD UNIVERSAL_GND..1
(-4350 5850);
FORCEPROP 3 LASTPIN (-4350 5900) SIG_NAME GND\g
J 0
(-4340 5910);
DISPLAY 0.659574 (-4340 5910);
PAINT MONO (-4340 5910);
DISPLAY INVISIBLE (-4340 5910);
FORCEPROP 2 LAST CDS_LIB pure_quanta_power
J 0
(-4350 5850);
DISPLAY INVISIBLE (-4350 5850);
FORCEPROP 1 LAST HDL_POWER GND
J 1
(-4325 5775);
DISPLAY 0.872340 (-4325 5775);
PAINT GREEN (-4325 5775);
DISPLAY INVISIBLE (-4325 5775);
FORCEPROP 1 LAST PATH I154
J 0
(-4275 5850);
DISPLAY 0.872340 (-4275 5850);
PAINT AQUA (-4275 5850);
DISPLAY INVISIBLE (-4275 5850);
FORCEADD UNIVERSAL_GND..1
(-4350 5225);
FORCEPROP 3 LASTPIN (-4350 5275) SIG_NAME GND\g
J 0
(-4340 5285);
DISPLAY 0.659574 (-4340 5285);
PAINT MONO (-4340 5285);
DISPLAY INVISIBLE (-4340 5285);
FORCEPROP 2 LAST CDS_LIB pure_quanta_power
J 0
(-4350 5225);
DISPLAY INVISIBLE (-4350 5225);
FORCEPROP 1 LAST HDL_POWER GND
J 1
(-4325 5150);
DISPLAY 0.872340 (-4325 5150);
PAINT GREEN (-4325 5150);
DISPLAY INVISIBLE (-4325 5150);
FORCEPROP 1 LAST PATH I155
J 0
(-4275 5225);
DISPLAY 0.872340 (-4275 5225);
PAINT AQUA (-4275 5225);
DISPLAY INVISIBLE (-4275 5225);
FORCEADD HOLE..1
(-4075 5300);
FORCEPROP 1 LAST LOCATION H102
J 0
(-4200 5535);
DISPLAY 0.723404 (-4200 5535);
PAINT GREEN (-4200 5535);
FORCEPROP 0 LAST $SEC 1
J 0
(-4200 5625);
DISPLAY 0.680851 (-4200 5625);
PAINT MONO (-4200 5625);
DISPLAY INVISIBLE (-4200 5625);
FORCEPROP 0 LAST CDS_SEC 1
J 0
(-4200 5625);
DISPLAY 0.680851 (-4200 5625);
DISPLAY INVISIBLE (-4200 5625);
FORCEPROP 0 LASTPIN (-4275 5325) $PN 1
J 2
(-4285 5335);
DISPLAY 0.680851 (-4285 5335);
PAINT MONO (-4285 5335);
FORCEPROP 1 LAST MATERIAL EMPTY
J 0
(-4200 5435);
DISPLAY 0.723404 (-4200 5435);
PAINT GREEN (-4200 5435);
FORCEPROP 2 LAST PACK_TYPE TH
J 0
(-4200 5575);
DISPLAY 0.680851 (-4200 5575);
FORCEPROP 2 LAST CDS_LIB pure_quanta
J 0
(-4075 5300);
DISPLAY INVISIBLE (-4075 5300);
FORCEPROP 1 LAST NEEDS_NO_SIZE TRUE
J 0
(-4075 5300);
DISPLAY 0.468085 (-4075 5300);
PAINT GREEN (-4075 5300);
DISPLAY INVISIBLE (-4075 5300);
FORCEPROP 1 LAST PATH I156
J 0
(-4025 5430);
DISPLAY 0.723404 (-4025 5430);
PAINT GREEN (-4025 5430);
DISPLAY INVISIBLE (-4025 5430);
FORCEPROP 1 LAST PART_NUMBER HOLE596
J 0
(-4200 5480);
DISPLAY 0.723404 (-4200 5480);
PAINT GREEN (-4200 5480);
DISPLAY INVISIBLE (-4200 5480);
FORCEADD HOLE..1
(-3325 5950);
FORCEPROP 1 LAST LOCATION H103
J 0
(-3450 6185);
DISPLAY 0.723404 (-3450 6185);
PAINT GREEN (-3450 6185);
FORCEPROP 0 LAST $SEC 1
J 0
(-3450 6275);
DISPLAY 0.680851 (-3450 6275);
PAINT MONO (-3450 6275);
DISPLAY INVISIBLE (-3450 6275);
FORCEPROP 0 LAST CDS_SEC 1
J 0
(-3450 6275);
DISPLAY 0.680851 (-3450 6275);
DISPLAY INVISIBLE (-3450 6275);
FORCEPROP 0 LASTPIN (-3525 5975) $PN 1
J 2
(-3535 5985);
DISPLAY 0.680851 (-3535 5985);
PAINT MONO (-3535 5985);
FORCEPROP 1 LAST MATERIAL EMPTY
J 0
(-3450 6085);
DISPLAY 0.723404 (-3450 6085);
PAINT GREEN (-3450 6085);
FORCEPROP 2 LAST PACK_TYPE TH
J 0
(-3450 6225);
DISPLAY 0.680851 (-3450 6225);
FORCEPROP 1 LAST NEEDS_NO_SIZE TRUE
J 0
(-3325 5950);
DISPLAY 0.468085 (-3325 5950);
PAINT GREEN (-3325 5950);
DISPLAY INVISIBLE (-3325 5950);
FORCEPROP 2 LAST CDS_LIB pure_quanta
J 0
(-3325 5950);
DISPLAY INVISIBLE (-3325 5950);
FORCEPROP 1 LAST PATH I157
J 0
(-3275 6080);
DISPLAY 0.723404 (-3275 6080);
PAINT GREEN (-3275 6080);
DISPLAY INVISIBLE (-3275 6080);
FORCEPROP 1 LAST PART_NUMBER HOLE596
J 0
(-3450 6130);
DISPLAY 0.723404 (-3450 6130);
PAINT GREEN (-3450 6130);
DISPLAY INVISIBLE (-3450 6130);
FORCEADD UNIVERSAL_GND..1
(-3575 5875);
FORCEPROP 3 LASTPIN (-3575 5925) SIG_NAME GND\g
J 0
(-3565 5935);
DISPLAY 0.659574 (-3565 5935);
PAINT MONO (-3565 5935);
DISPLAY INVISIBLE (-3565 5935);
FORCEPROP 2 LAST CDS_LIB pure_quanta_power
J 0
(-3575 5875);
DISPLAY INVISIBLE (-3575 5875);
FORCEPROP 1 LAST HDL_POWER GND
J 1
(-3550 5800);
DISPLAY 0.872340 (-3550 5800);
PAINT GREEN (-3550 5800);
DISPLAY INVISIBLE (-3550 5800);
FORCEPROP 1 LAST PATH I158
J 0
(-3500 5875);
DISPLAY 0.872340 (-3500 5875);
PAINT AQUA (-3500 5875);
DISPLAY INVISIBLE (-3500 5875);
FORCEADD HOLE..1
(-3325 5325);
FORCEPROP 1 LAST LOCATION H104
J 0
(-3450 5560);
DISPLAY 0.723404 (-3450 5560);
PAINT GREEN (-3450 5560);
FORCEPROP 0 LAST $SEC 1
J 0
(-3450 5650);
DISPLAY 0.680851 (-3450 5650);
PAINT MONO (-3450 5650);
DISPLAY INVISIBLE (-3450 5650);
FORCEPROP 0 LAST CDS_SEC 1
J 0
(-3450 5650);
DISPLAY 0.680851 (-3450 5650);
DISPLAY INVISIBLE (-3450 5650);
FORCEPROP 0 LASTPIN (-3525 5350) $PN 1
J 2
(-3535 5360);
DISPLAY 0.680851 (-3535 5360);
PAINT MONO (-3535 5360);
FORCEPROP 2 LAST PACK_TYPE TH
J 0
(-3450 5600);
DISPLAY 0.680851 (-3450 5600);
FORCEPROP 1 LAST MATERIAL EMPTY
J 0
(-3450 5460);
DISPLAY 0.723404 (-3450 5460);
PAINT GREEN (-3450 5460);
FORCEPROP 1 LAST NEEDS_NO_SIZE TRUE
J 0
(-3325 5325);
DISPLAY 0.468085 (-3325 5325);
PAINT GREEN (-3325 5325);
DISPLAY INVISIBLE (-3325 5325);
FORCEPROP 2 LAST CDS_LIB pure_quanta
J 0
(-3325 5325);
DISPLAY INVISIBLE (-3325 5325);
FORCEPROP 1 LAST PATH I159
J 0
(-3275 5455);
DISPLAY 0.723404 (-3275 5455);
PAINT GREEN (-3275 5455);
DISPLAY INVISIBLE (-3275 5455);
FORCEPROP 1 LAST PART_NUMBER HOLE596
J 0
(-3450 5505);
DISPLAY 0.723404 (-3450 5505);
PAINT GREEN (-3450 5505);
DISPLAY INVISIBLE (-3450 5505);
FORCEADD UNIVERSAL_GND..1
(-3600 5250);
FORCEPROP 3 LASTPIN (-3600 5300) SIG_NAME GND\g
J 0
(-3590 5310);
DISPLAY 0.659574 (-3590 5310);
PAINT MONO (-3590 5310);
DISPLAY INVISIBLE (-3590 5310);
FORCEPROP 2 LAST CDS_LIB pure_quanta_power
J 0
(-3600 5250);
DISPLAY INVISIBLE (-3600 5250);
FORCEPROP 1 LAST HDL_POWER GND
J 1
(-3575 5175);
DISPLAY 0.872340 (-3575 5175);
PAINT GREEN (-3575 5175);
DISPLAY INVISIBLE (-3575 5175);
FORCEPROP 1 LAST PATH I160
J 0
(-3525 5250);
DISPLAY 0.872340 (-3525 5250);
PAINT AQUA (-3525 5250);
DISPLAY INVISIBLE (-3525 5250);
FORCEADD HOLE..1
(-2675 5950);
FORCEPROP 1 LAST LOCATION H105
J 0
(-2800 6185);
DISPLAY 0.723404 (-2800 6185);
PAINT GREEN (-2800 6185);
FORCEPROP 0 LAST $SEC 1
J 0
(-2800 6275);
DISPLAY 0.680851 (-2800 6275);
PAINT MONO (-2800 6275);
DISPLAY INVISIBLE (-2800 6275);
FORCEPROP 0 LAST CDS_SEC 1
J 0
(-2800 6275);
DISPLAY 0.680851 (-2800 6275);
DISPLAY INVISIBLE (-2800 6275);
FORCEPROP 0 LASTPIN (-2875 5975) $PN 1
J 2
(-2885 5985);
DISPLAY 0.680851 (-2885 5985);
PAINT MONO (-2885 5985);
FORCEPROP 1 LAST MATERIAL EMPTY
J 0
(-2800 6085);
DISPLAY 0.723404 (-2800 6085);
PAINT GREEN (-2800 6085);
FORCEPROP 2 LAST PACK_TYPE TH
J 0
(-2800 6225);
DISPLAY 0.680851 (-2800 6225);
FORCEPROP 2 LAST CDS_LIB pure_quanta
J 0
(-2675 5950);
DISPLAY INVISIBLE (-2675 5950);
FORCEPROP 1 LAST NEEDS_NO_SIZE TRUE
J 0
(-2675 5950);
DISPLAY 0.468085 (-2675 5950);
PAINT GREEN (-2675 5950);
DISPLAY INVISIBLE (-2675 5950);
FORCEPROP 1 LAST PATH I161
J 0
(-2625 6080);
DISPLAY 0.723404 (-2625 6080);
PAINT GREEN (-2625 6080);
DISPLAY INVISIBLE (-2625 6080);
FORCEPROP 1 LAST PART_NUMBER HOLE596
J 0
(-2800 6130);
DISPLAY 0.723404 (-2800 6130);
PAINT GREEN (-2800 6130);
DISPLAY INVISIBLE (-2800 6130);
FORCEADD UNIVERSAL_GND..1
(-2925 5875);
FORCEPROP 3 LASTPIN (-2925 5925) SIG_NAME GND\g
J 0
(-2915 5935);
DISPLAY 0.659574 (-2915 5935);
PAINT MONO (-2915 5935);
DISPLAY INVISIBLE (-2915 5935);
FORCEPROP 2 LAST CDS_LIB pure_quanta_power
J 0
(-2925 5875);
DISPLAY INVISIBLE (-2925 5875);
FORCEPROP 1 LAST HDL_POWER GND
J 1
(-2900 5800);
DISPLAY 0.872340 (-2900 5800);
PAINT GREEN (-2900 5800);
DISPLAY INVISIBLE (-2900 5800);
FORCEPROP 1 LAST PATH I162
J 0
(-2850 5875);
DISPLAY 0.872340 (-2850 5875);
PAINT AQUA (-2850 5875);
DISPLAY INVISIBLE (-2850 5875);
FORCEADD HOLE..1
(-2675 5300);
FORCEPROP 1 LAST LOCATION H106
J 0
(-2800 5535);
DISPLAY 0.723404 (-2800 5535);
PAINT GREEN (-2800 5535);
FORCEPROP 0 LAST $SEC 1
J 0
(-2800 5625);
DISPLAY 0.680851 (-2800 5625);
PAINT MONO (-2800 5625);
DISPLAY INVISIBLE (-2800 5625);
FORCEPROP 0 LAST CDS_SEC 1
J 0
(-2800 5625);
DISPLAY 0.680851 (-2800 5625);
DISPLAY INVISIBLE (-2800 5625);
FORCEPROP 0 LASTPIN (-2875 5325) $PN 1
J 2
(-2885 5335);
DISPLAY 0.680851 (-2885 5335);
PAINT MONO (-2885 5335);
FORCEPROP 1 LAST MATERIAL EMPTY
J 0
(-2800 5435);
DISPLAY 0.723404 (-2800 5435);
PAINT GREEN (-2800 5435);
FORCEPROP 2 LAST PACK_TYPE TH
J 0
(-2800 5575);
DISPLAY 0.680851 (-2800 5575);
FORCEPROP 1 LAST NEEDS_NO_SIZE TRUE
J 0
(-2675 5300);
DISPLAY 0.468085 (-2675 5300);
PAINT GREEN (-2675 5300);
DISPLAY INVISIBLE (-2675 5300);
FORCEPROP 2 LAST CDS_LIB pure_quanta
J 0
(-2675 5300);
DISPLAY INVISIBLE (-2675 5300);
FORCEPROP 1 LAST PATH I163
J 0
(-2625 5430);
DISPLAY 0.723404 (-2625 5430);
PAINT GREEN (-2625 5430);
DISPLAY INVISIBLE (-2625 5430);
FORCEPROP 1 LAST PART_NUMBER HOLE596
J 0
(-2800 5480);
DISPLAY 0.723404 (-2800 5480);
PAINT GREEN (-2800 5480);
DISPLAY INVISIBLE (-2800 5480);
FORCEADD UNIVERSAL_GND..1
(-2925 5225);
FORCEPROP 3 LASTPIN (-2925 5275) SIG_NAME GND\g
J 0
(-2915 5285);
DISPLAY 0.659574 (-2915 5285);
PAINT MONO (-2915 5285);
DISPLAY INVISIBLE (-2915 5285);
FORCEPROP 2 LAST CDS_LIB pure_quanta_power
J 0
(-2925 5225);
DISPLAY INVISIBLE (-2925 5225);
FORCEPROP 1 LAST HDL_POWER GND
J 1
(-2900 5150);
DISPLAY 0.872340 (-2900 5150);
PAINT GREEN (-2900 5150);
DISPLAY INVISIBLE (-2900 5150);
FORCEPROP 1 LAST PATH I164
J 0
(-2850 5225);
DISPLAY 0.872340 (-2850 5225);
PAINT AQUA (-2850 5225);
DISPLAY INVISIBLE (-2850 5225);
FORCEADD UNIVERSAL_GND..1
(-2250 5925);
FORCEPROP 3 LASTPIN (-2250 5975) SIG_NAME GND\g
J 0
(-2240 5985);
DISPLAY 0.659574 (-2240 5985);
PAINT MONO (-2240 5985);
DISPLAY INVISIBLE (-2240 5985);
FORCEPROP 2 LAST CDS_LIB pure_quanta_power
J 0
(-2250 5925);
DISPLAY INVISIBLE (-2250 5925);
FORCEPROP 1 LAST HDL_POWER GND
J 1
(-2225 5850);
DISPLAY 0.872340 (-2225 5850);
PAINT GREEN (-2225 5850);
DISPLAY INVISIBLE (-2225 5850);
FORCEPROP 1 LAST PATH I165
J 0
(-2175 5925);
DISPLAY 0.872340 (-2175 5925);
PAINT AQUA (-2175 5925);
DISPLAY INVISIBLE (-2175 5925);
FORCEADD HOLE..1
(-2000 6000);
FORCEPROP 1 LAST LOCATION H128
J 0
(-2125 6235);
DISPLAY 0.723404 (-2125 6235);
PAINT GREEN (-2125 6235);
FORCEPROP 0 LAST $SEC 1
J 0
(-2125 6325);
DISPLAY 0.680851 (-2125 6325);
PAINT MONO (-2125 6325);
DISPLAY INVISIBLE (-2125 6325);
FORCEPROP 0 LAST CDS_SEC 1
J 0
(-2125 6325);
DISPLAY 0.680851 (-2125 6325);
DISPLAY INVISIBLE (-2125 6325);
FORCEPROP 0 LASTPIN (-2200 6025) $PN 1
J 2
(-2210 6035);
DISPLAY 0.680851 (-2210 6035);
PAINT MONO (-2210 6035);
FORCEPROP 1 LAST MATERIAL EMPTY
J 0
(-2125 6135);
DISPLAY 0.723404 (-2125 6135);
PAINT GREEN (-2125 6135);
FORCEPROP 2 LAST PACK_TYPE TH
J 0
(-2125 6275);
DISPLAY 0.680851 (-2125 6275);
FORCEPROP 1 LAST NEEDS_NO_SIZE TRUE
J 0
(-2000 6000);
DISPLAY 0.468085 (-2000 6000);
PAINT GREEN (-2000 6000);
DISPLAY INVISIBLE (-2000 6000);
FORCEPROP 2 LAST CDS_LIB pure_quanta
J 0
(-2000 6000);
DISPLAY INVISIBLE (-2000 6000);
FORCEPROP 1 LAST PATH I166
J 0
(-1950 6130);
DISPLAY 0.723404 (-1950 6130);
PAINT GREEN (-1950 6130);
DISPLAY INVISIBLE (-1950 6130);
FORCEPROP 1 LAST PART_NUMBER HOLE596
J 0
(-2125 6180);
DISPLAY 0.723404 (-2125 6180);
PAINT GREEN (-2125 6180);
DISPLAY INVISIBLE (-2125 6180);
FORCEADD HOLE..1
(-825 6025);
FORCEPROP 1 LAST LOCATION H90
J 0
(-950 6260);
DISPLAY 0.723404 (-950 6260);
PAINT GREEN (-950 6260);
FORCEPROP 0 LAST $SEC 1
J 0
(-950 6350);
DISPLAY 0.680851 (-950 6350);
PAINT MONO (-950 6350);
DISPLAY INVISIBLE (-950 6350);
FORCEPROP 0 LAST CDS_SEC 1
J 0
(-950 6350);
DISPLAY 0.680851 (-950 6350);
DISPLAY INVISIBLE (-950 6350);
FORCEPROP 0 LASTPIN (-1025 6050) $PN 1
J 2
(-1035 6060);
DISPLAY 0.680851 (-1035 6060);
PAINT MONO (-1035 6060);
FORCEPROP 1 LAST MATERIAL EMPTY
J 0
(-950 6160);
DISPLAY 0.723404 (-950 6160);
PAINT GREEN (-950 6160);
FORCEPROP 2 LAST PACK_TYPE TH
J 0
(-950 6300);
DISPLAY 0.680851 (-950 6300);
FORCEPROP 2 LAST CDS_LIB pure_quanta
J 0
(-825 6025);
DISPLAY INVISIBLE (-825 6025);
FORCEPROP 1 LAST NEEDS_NO_SIZE TRUE
J 0
(-825 6025);
DISPLAY 0.468085 (-825 6025);
PAINT GREEN (-825 6025);
DISPLAY INVISIBLE (-825 6025);
FORCEPROP 1 LAST PATH I167
J 0
(-775 6155);
DISPLAY 0.723404 (-775 6155);
PAINT GREEN (-775 6155);
DISPLAY INVISIBLE (-775 6155);
FORCEPROP 1 LAST PART_NUMBER HOLE372
J 0
(-950 6205);
DISPLAY 0.723404 (-950 6205);
PAINT GREEN (-950 6205);
DISPLAY INVISIBLE (-950 6205);
FORCEADD HOLE..1
(-525 3975);
FORCEPROP 1 LAST LOCATION H6002
J 0
(-650 4210);
DISPLAY 0.723404 (-650 4210);
PAINT GREEN (-650 4210);
FORCEPROP 0 LAST $SEC 1
J 0
(-650 4300);
DISPLAY 0.680851 (-650 4300);
PAINT MONO (-650 4300);
DISPLAY INVISIBLE (-650 4300);
FORCEPROP 0 LAST CDS_SEC 1
J 0
(-650 4300);
DISPLAY 0.680851 (-650 4300);
DISPLAY INVISIBLE (-650 4300);
FORCEPROP 0 LASTPIN (-725 4000) $PN 1
J 2
(-735 4010);
DISPLAY 0.680851 (-735 4010);
PAINT MONO (-735 4010);
FORCEPROP 1 LAST MATERIAL EMPTY
J 0
(-650 4110);
DISPLAY 0.723404 (-650 4110);
PAINT GREEN (-650 4110);
FORCEPROP 2 LAST PACK_TYPE TH
J 0
(-650 4250);
DISPLAY 0.680851 (-650 4250);
FORCEPROP 1 LAST NEEDS_NO_SIZE TRUE
J 0
(-525 3975);
DISPLAY 0.468085 (-525 3975);
PAINT GREEN (-525 3975);
DISPLAY INVISIBLE (-525 3975);
FORCEPROP 2 LAST CDS_LIB pure_quanta
J 0
(-525 3975);
DISPLAY INVISIBLE (-525 3975);
FORCEPROP 1 LAST PATH I168
J 0
(-475 4105);
DISPLAY 0.723404 (-475 4105);
PAINT GREEN (-475 4105);
DISPLAY INVISIBLE (-475 4105);
FORCEPROP 1 LAST PART_NUMBER HOLE1195
J 0
(-650 4155);
DISPLAY 0.723404 (-650 4155);
PAINT GREEN (-650 4155);
DISPLAY INVISIBLE (-650 4155);
FORCEADD UNIVERSAL_GND..1
(-850 3800);
FORCEPROP 3 LASTPIN (-850 3850) SIG_NAME GND\g
J 0
(-840 3860);
DISPLAY 0.659574 (-840 3860);
PAINT MONO (-840 3860);
DISPLAY INVISIBLE (-840 3860);
FORCEPROP 2 LAST CDS_LIB pure_quanta_power
J 0
(-850 3800);
DISPLAY INVISIBLE (-850 3800);
FORCEPROP 1 LAST HDL_POWER GND
J 1
(-825 3725);
DISPLAY 0.872340 (-825 3725);
PAINT GREEN (-825 3725);
DISPLAY INVISIBLE (-825 3725);
FORCEPROP 1 LAST PATH I169
J 0
(-775 3800);
DISPLAY 0.872340 (-775 3800);
PAINT AQUA (-775 3800);
DISPLAY INVISIBLE (-775 3800);
FORCEADD HOLE..1
(-8775 2175);
FORCEPROP 1 LAST LOCATION H2
J 0
(-8900 2410);
DISPLAY 0.489362 (-8900 2410);
PAINT SKYBLUE (-8900 2410);
FORCEPROP 0 LAST $SEC 1
J 0
(-8900 2475);
DISPLAY 0.680851 (-8900 2475);
PAINT MONO (-8900 2475);
DISPLAY INVISIBLE (-8900 2475);
FORCEPROP 0 LAST CDS_SEC 1
J 0
(-8900 2475);
DISPLAY 0.680851 (-8900 2475);
DISPLAY INVISIBLE (-8900 2475);
FORCEPROP 0 LASTPIN (-8975 2200) $PN 1
J 2
(-8985 2210);
DISPLAY 0.680851 (-8985 2210);
PAINT MONO (-8985 2210);
FORCEPROP 1 LAST MATERIAL EMPTY
J 0
(-8900 2310);
DISPLAY 0.489362 (-8900 2310);
PAINT RED (-8900 2310);
FORCEPROP 2 LAST PACK_TYPE TH
J 0
(-8900 2450);
DISPLAY 0.489362 (-8900 2450);
PAINT SKYBLUE (-8900 2450);
FORCEPROP 2 LAST CDS_LIB pure_quanta
J 0
(-8775 2175);
DISPLAY INVISIBLE (-8775 2175);
FORCEPROP 1 LAST NEEDS_NO_SIZE TRUE
J 0
(-8775 2175);
DISPLAY 0.468085 (-8775 2175);
PAINT GREEN (-8775 2175);
DISPLAY INVISIBLE (-8775 2175);
FORCEPROP 1 LAST PATH I170
J 0
(-8725 2305);
DISPLAY 0.723404 (-8725 2305);
PAINT GREEN (-8725 2305);
DISPLAY INVISIBLE (-8725 2305);
FORCEPROP 1 LAST PART_NUMBER HOLE1226
J 0
(-8900 2355);
DISPLAY 0.489362 (-8900 2355);
PAINT SKYBLUE (-8900 2355);
DISPLAY INVISIBLE (-8900 2355);
FORCEADD UNIVERSAL_GND..1
(-8975 2100);
FORCEPROP 3 LASTPIN (-8975 2150) SIG_NAME GND\g
J 0
(-8965 2160);
DISPLAY 0.659574 (-8965 2160);
PAINT MONO (-8965 2160);
DISPLAY INVISIBLE (-8965 2160);
FORCEPROP 2 LAST CDS_LIB pure_quanta_power
J 0
(-8975 2100);
DISPLAY INVISIBLE (-8975 2100);
FORCEPROP 1 LAST HDL_POWER GND
J 1
(-8950 2025);
DISPLAY 0.872340 (-8950 2025);
PAINT GREEN (-8950 2025);
DISPLAY INVISIBLE (-8950 2025);
FORCEPROP 1 LAST PATH I171
J 0
(-8900 2100);
DISPLAY 0.872340 (-8900 2100);
PAINT AQUA (-8900 2100);
DISPLAY INVISIBLE (-8900 2100);
FORCEADD HOLE..1
(-8175 2125);
FORCEPROP 1 LAST LOCATION H8
J 0
(-8300 2360);
DISPLAY 0.489362 (-8300 2360);
PAINT SKYBLUE (-8300 2360);
FORCEPROP 0 LAST $SEC 1
J 0
(-8300 2425);
DISPLAY 0.680851 (-8300 2425);
PAINT MONO (-8300 2425);
DISPLAY INVISIBLE (-8300 2425);
FORCEPROP 0 LAST CDS_SEC 1
J 0
(-8300 2425);
DISPLAY 0.680851 (-8300 2425);
DISPLAY INVISIBLE (-8300 2425);
FORCEPROP 0 LASTPIN (-8375 2150) $PN 1
J 2
(-8385 2160);
DISPLAY 0.680851 (-8385 2160);
PAINT MONO (-8385 2160);
FORCEPROP 2 LAST PACK_TYPE TH
J 0
(-8300 2400);
DISPLAY 0.489362 (-8300 2400);
PAINT SKYBLUE (-8300 2400);
FORCEPROP 1 LAST MATERIAL EMPTY
J 0
(-8300 2260);
DISPLAY 0.489362 (-8300 2260);
PAINT RED (-8300 2260);
FORCEPROP 1 LAST NEEDS_NO_SIZE TRUE
J 0
(-8175 2125);
DISPLAY 0.468085 (-8175 2125);
PAINT GREEN (-8175 2125);
DISPLAY INVISIBLE (-8175 2125);
FORCEPROP 2 LAST CDS_LIB pure_quanta
J 0
(-8175 2125);
DISPLAY INVISIBLE (-8175 2125);
FORCEPROP 1 LAST PATH I176
J 0
(-8125 2255);
DISPLAY 0.723404 (-8125 2255);
PAINT GREEN (-8125 2255);
DISPLAY INVISIBLE (-8125 2255);
FORCEPROP 1 LAST PART_NUMBER HOLE1226
J 0
(-8300 2305);
DISPLAY 0.489362 (-8300 2305);
PAINT SKYBLUE (-8300 2305);
DISPLAY INVISIBLE (-8300 2305);
FORCEADD UNIVERSAL_GND..1
(-8375 2050);
FORCEPROP 3 LASTPIN (-8375 2100) SIG_NAME GND\g
J 0
(-8365 2110);
DISPLAY 0.659574 (-8365 2110);
PAINT MONO (-8365 2110);
DISPLAY INVISIBLE (-8365 2110);
FORCEPROP 2 LAST CDS_LIB pure_quanta_power
J 0
(-8375 2050);
DISPLAY INVISIBLE (-8375 2050);
FORCEPROP 1 LAST HDL_POWER GND
J 1
(-8350 1975);
DISPLAY 0.872340 (-8350 1975);
PAINT GREEN (-8350 1975);
DISPLAY INVISIBLE (-8350 1975);
FORCEPROP 1 LAST PATH I177
J 0
(-8300 2050);
DISPLAY 0.872340 (-8300 2050);
PAINT AQUA (-8300 2050);
DISPLAY INVISIBLE (-8300 2050);
FORCEADD HOLE..1
(-7675 2100);
FORCEPROP 1 LAST LOCATION H10
J 0
(-7800 2335);
DISPLAY 0.489362 (-7800 2335);
PAINT SKYBLUE (-7800 2335);
FORCEPROP 0 LAST $SEC 1
J 0
(-7800 2400);
DISPLAY 0.680851 (-7800 2400);
PAINT MONO (-7800 2400);
DISPLAY INVISIBLE (-7800 2400);
FORCEPROP 0 LAST CDS_SEC 1
J 0
(-7800 2400);
DISPLAY 0.680851 (-7800 2400);
DISPLAY INVISIBLE (-7800 2400);
FORCEPROP 0 LASTPIN (-7875 2125) $PN 1
J 2
(-7885 2135);
DISPLAY 0.680851 (-7885 2135);
PAINT MONO (-7885 2135);
FORCEPROP 2 LAST PACK_TYPE TH
J 0
(-7800 2375);
DISPLAY 0.489362 (-7800 2375);
PAINT SKYBLUE (-7800 2375);
FORCEPROP 1 LAST MATERIAL EMPTY
J 0
(-7800 2235);
DISPLAY 0.489362 (-7800 2235);
PAINT RED (-7800 2235);
FORCEPROP 1 LAST NEEDS_NO_SIZE TRUE
J 0
(-7675 2100);
DISPLAY 0.468085 (-7675 2100);
PAINT GREEN (-7675 2100);
DISPLAY INVISIBLE (-7675 2100);
FORCEPROP 2 LAST CDS_LIB pure_quanta
J 0
(-7675 2100);
DISPLAY INVISIBLE (-7675 2100);
FORCEPROP 1 LAST PATH I178
J 0
(-7625 2230);
DISPLAY 0.723404 (-7625 2230);
PAINT GREEN (-7625 2230);
DISPLAY INVISIBLE (-7625 2230);
FORCEPROP 1 LAST PART_NUMBER HOLE1226
J 0
(-7800 2280);
DISPLAY 0.489362 (-7800 2280);
PAINT SKYBLUE (-7800 2280);
DISPLAY INVISIBLE (-7800 2280);
FORCEADD UNIVERSAL_GND..1
(-7875 2025);
FORCEPROP 3 LASTPIN (-7875 2075) SIG_NAME GND\g
J 0
(-7865 2085);
DISPLAY 0.659574 (-7865 2085);
PAINT MONO (-7865 2085);
DISPLAY INVISIBLE (-7865 2085);
FORCEPROP 2 LAST CDS_LIB pure_quanta_power
J 0
(-7875 2025);
DISPLAY INVISIBLE (-7875 2025);
FORCEPROP 1 LAST HDL_POWER GND
J 1
(-7850 1950);
DISPLAY 0.872340 (-7850 1950);
PAINT GREEN (-7850 1950);
DISPLAY INVISIBLE (-7850 1950);
FORCEPROP 1 LAST PATH I179
J 0
(-7800 2025);
DISPLAY 0.872340 (-7800 2025);
PAINT AQUA (-7800 2025);
DISPLAY INVISIBLE (-7800 2025);
FORCEADD UNIVERSAL_GND..1
(-6225 2050);
FORCEPROP 3 LASTPIN (-6225 2100) SIG_NAME GND\g
J 0
(-6215 2110);
DISPLAY 0.659574 (-6215 2110);
PAINT MONO (-6215 2110);
DISPLAY INVISIBLE (-6215 2110);
FORCEPROP 2 LAST CDS_LIB pure_quanta_power
J 0
(-6225 2050);
DISPLAY INVISIBLE (-6225 2050);
FORCEPROP 1 LAST HDL_POWER GND
J 1
(-6200 1975);
DISPLAY 0.872340 (-6200 1975);
PAINT GREEN (-6200 1975);
DISPLAY INVISIBLE (-6200 1975);
FORCEPROP 1 LAST PATH I186
J 0
(-6150 2050);
DISPLAY 0.872340 (-6150 2050);
PAINT AQUA (-6150 2050);
DISPLAY INVISIBLE (-6150 2050);
FORCEADD HOLE..1
(-6025 2125);
FORCEPROP 1 LAST LOCATION H12
J 0
(-6150 2360);
DISPLAY 0.489362 (-6150 2360);
PAINT SKYBLUE (-6150 2360);
FORCEPROP 0 LAST $SEC 1
J 0
(-6150 2425);
DISPLAY 0.680851 (-6150 2425);
PAINT MONO (-6150 2425);
DISPLAY INVISIBLE (-6150 2425);
FORCEPROP 0 LAST CDS_SEC 1
J 0
(-6150 2425);
DISPLAY 0.680851 (-6150 2425);
DISPLAY INVISIBLE (-6150 2425);
FORCEPROP 0 LASTPIN (-6225 2150) $PN 1
J 2
(-6235 2160);
DISPLAY 0.680851 (-6235 2160);
PAINT MONO (-6235 2160);
FORCEPROP 1 LAST MATERIAL EMPTY
J 0
(-6150 2260);
DISPLAY 0.489362 (-6150 2260);
PAINT RED (-6150 2260);
FORCEPROP 2 LAST PACK_TYPE TH
J 0
(-6150 2400);
DISPLAY 0.489362 (-6150 2400);
PAINT SKYBLUE (-6150 2400);
FORCEPROP 2 LAST CDS_LIB pure_quanta
J 0
(-6025 2125);
DISPLAY INVISIBLE (-6025 2125);
FORCEPROP 1 LAST NEEDS_NO_SIZE TRUE
J 0
(-6025 2125);
DISPLAY 0.468085 (-6025 2125);
PAINT GREEN (-6025 2125);
DISPLAY INVISIBLE (-6025 2125);
FORCEPROP 1 LAST PATH I187
J 0
(-5975 2255);
DISPLAY 0.723404 (-5975 2255);
PAINT GREEN (-5975 2255);
DISPLAY INVISIBLE (-5975 2255);
FORCEPROP 1 LAST PART_NUMBER HOLE1226
J 0
(-6150 2305);
DISPLAY 0.489362 (-6150 2305);
PAINT SKYBLUE (-6150 2305);
DISPLAY INVISIBLE (-6150 2305);
FORCEADD UNIVERSAL_GND..1
(-6775 2050);
FORCEPROP 3 LASTPIN (-6775 2100) SIG_NAME GND\g
J 0
(-6765 2110);
DISPLAY 0.659574 (-6765 2110);
PAINT MONO (-6765 2110);
DISPLAY INVISIBLE (-6765 2110);
FORCEPROP 2 LAST CDS_LIB pure_quanta_power
J 0
(-6775 2050);
DISPLAY INVISIBLE (-6775 2050);
FORCEPROP 1 LAST HDL_POWER GND
J 1
(-6750 1975);
DISPLAY 0.872340 (-6750 1975);
PAINT GREEN (-6750 1975);
DISPLAY INVISIBLE (-6750 1975);
FORCEPROP 1 LAST PATH I192
J 0
(-6700 2050);
DISPLAY 0.872340 (-6700 2050);
PAINT AQUA (-6700 2050);
DISPLAY INVISIBLE (-6700 2050);
FORCEADD HOLE..1
(-6575 2125);
FORCEPROP 1 LAST LOCATION H5
J 0
(-6700 2360);
DISPLAY 0.489362 (-6700 2360);
PAINT SKYBLUE (-6700 2360);
FORCEPROP 0 LAST $SEC 1
J 0
(-6700 2425);
DISPLAY 0.680851 (-6700 2425);
PAINT MONO (-6700 2425);
DISPLAY INVISIBLE (-6700 2425);
FORCEPROP 0 LAST CDS_SEC 1
J 0
(-6700 2425);
DISPLAY 0.680851 (-6700 2425);
DISPLAY INVISIBLE (-6700 2425);
FORCEPROP 0 LASTPIN (-6775 2150) $PN 1
J 2
(-6785 2160);
DISPLAY 0.680851 (-6785 2160);
PAINT MONO (-6785 2160);
FORCEPROP 1 LAST MATERIAL EMPTY
J 0
(-6700 2260);
DISPLAY 0.489362 (-6700 2260);
PAINT RED (-6700 2260);
FORCEPROP 2 LAST PACK_TYPE TH
J 0
(-6700 2400);
DISPLAY 0.489362 (-6700 2400);
PAINT SKYBLUE (-6700 2400);
FORCEPROP 1 LAST NEEDS_NO_SIZE TRUE
J 0
(-6575 2125);
DISPLAY 0.468085 (-6575 2125);
PAINT GREEN (-6575 2125);
DISPLAY INVISIBLE (-6575 2125);
FORCEPROP 2 LAST CDS_LIB pure_quanta
J 0
(-6575 2125);
DISPLAY INVISIBLE (-6575 2125);
FORCEPROP 1 LAST PATH I193
J 0
(-6525 2255);
DISPLAY 0.723404 (-6525 2255);
PAINT GREEN (-6525 2255);
DISPLAY INVISIBLE (-6525 2255);
FORCEPROP 1 LAST PART_NUMBER HOLE1226
J 0
(-6700 2305);
DISPLAY 0.489362 (-6700 2305);
PAINT SKYBLUE (-6700 2305);
DISPLAY INVISIBLE (-6700 2305);
FORCEADD UNIVERSAL_GND..1
(-7325 2050);
FORCEPROP 3 LASTPIN (-7325 2100) SIG_NAME GND\g
J 0
(-7315 2110);
DISPLAY 0.659574 (-7315 2110);
PAINT MONO (-7315 2110);
DISPLAY INVISIBLE (-7315 2110);
FORCEPROP 2 LAST CDS_LIB pure_quanta_power
J 0
(-7325 2050);
DISPLAY INVISIBLE (-7325 2050);
FORCEPROP 1 LAST HDL_POWER GND
J 1
(-7300 1975);
DISPLAY 0.872340 (-7300 1975);
PAINT GREEN (-7300 1975);
DISPLAY INVISIBLE (-7300 1975);
FORCEPROP 1 LAST PATH I194
J 0
(-7250 2050);
DISPLAY 0.872340 (-7250 2050);
PAINT AQUA (-7250 2050);
DISPLAY INVISIBLE (-7250 2050);
FORCEADD HOLE..1
(-7125 2125);
FORCEPROP 1 LAST LOCATION H3
J 0
(-7250 2360);
DISPLAY 0.489362 (-7250 2360);
PAINT SKYBLUE (-7250 2360);
FORCEPROP 0 LAST $SEC 1
J 0
(-7250 2425);
DISPLAY 0.680851 (-7250 2425);
PAINT MONO (-7250 2425);
DISPLAY INVISIBLE (-7250 2425);
FORCEPROP 0 LAST CDS_SEC 1
J 0
(-7250 2425);
DISPLAY 0.680851 (-7250 2425);
DISPLAY INVISIBLE (-7250 2425);
FORCEPROP 0 LASTPIN (-7325 2150) $PN 1
J 2
(-7335 2160);
DISPLAY 0.680851 (-7335 2160);
PAINT MONO (-7335 2160);
FORCEPROP 1 LAST MATERIAL EMPTY
J 0
(-7250 2260);
DISPLAY 0.489362 (-7250 2260);
PAINT RED (-7250 2260);
FORCEPROP 2 LAST PACK_TYPE TH
J 0
(-7250 2400);
DISPLAY 0.489362 (-7250 2400);
PAINT SKYBLUE (-7250 2400);
FORCEPROP 1 LAST NEEDS_NO_SIZE TRUE
J 0
(-7125 2125);
DISPLAY 0.468085 (-7125 2125);
PAINT GREEN (-7125 2125);
DISPLAY INVISIBLE (-7125 2125);
FORCEPROP 2 LAST CDS_LIB pure_quanta
J 0
(-7125 2125);
DISPLAY INVISIBLE (-7125 2125);
FORCEPROP 1 LAST PATH I195
J 0
(-7075 2255);
DISPLAY 0.723404 (-7075 2255);
PAINT GREEN (-7075 2255);
DISPLAY INVISIBLE (-7075 2255);
FORCEPROP 1 LAST PART_NUMBER HOLE1226
J 0
(-7250 2305);
DISPLAY 0.489362 (-7250 2305);
PAINT SKYBLUE (-7250 2305);
DISPLAY INVISIBLE (-7250 2305);
FORCEADD UNIVERSAL_GND..1
(-8450 2725);
FORCEPROP 3 LASTPIN (-8450 2775) SIG_NAME GND\g
J 0
(-8440 2785);
DISPLAY 0.659574 (-8440 2785);
PAINT MONO (-8440 2785);
DISPLAY INVISIBLE (-8440 2785);
FORCEPROP 2 LAST CDS_LIB pure_quanta_power
J 0
(-8450 2725);
DISPLAY INVISIBLE (-8450 2725);
FORCEPROP 1 LAST HDL_POWER GND
J 1
(-8425 2650);
DISPLAY 0.872340 (-8425 2650);
PAINT GREEN (-8425 2650);
DISPLAY INVISIBLE (-8425 2650);
FORCEPROP 1 LAST PATH I21
J 0
(-8375 2725);
DISPLAY 0.872340 (-8375 2725);
PAINT AQUA (-8375 2725);
DISPLAY INVISIBLE (-8375 2725);
FORCEADD UNIVERSAL_GND..1
(-9125 450);
FORCEPROP 3 LASTPIN (-9125 500) SIG_NAME GND\g
J 0
(-9115 510);
DISPLAY 0.659574 (-9115 510);
PAINT MONO (-9115 510);
DISPLAY INVISIBLE (-9115 510);
FORCEPROP 2 LAST CDS_LIB pure_quanta_power
J 0
(-9125 450);
DISPLAY INVISIBLE (-9125 450);
FORCEPROP 1 LAST HDL_POWER GND
J 1
(-9100 375);
DISPLAY 0.872340 (-9100 375);
PAINT GREEN (-9100 375);
DISPLAY INVISIBLE (-9100 375);
FORCEPROP 1 LAST PATH I24
J 0
(-9050 450);
DISPLAY 0.872340 (-9050 450);
PAINT AQUA (-9050 450);
DISPLAY INVISIBLE (-9050 450);
FORCEADD GND_HOLE..1
(-8850 850);
FORCEPROP 1 LAST LOCATION H113
J 0
(-9000 1275);
DISPLAY 0.723404 (-9000 1275);
PAINT GREEN (-9000 1275);
FORCEPROP 0 LAST $SEC 1
J 0
(-9000 1375);
DISPLAY 0.680851 (-9000 1375);
PAINT MONO (-9000 1375);
DISPLAY INVISIBLE (-9000 1375);
FORCEPROP 0 LAST CDS_SEC 1
J 0
(-9000 1375);
DISPLAY 1.021277 (-9000 1375);
DISPLAY INVISIBLE (-9000 1375);
FORCEPROP 0 LASTPIN (-8650 850) $PN 2
J 0
(-8640 860);
DISPLAY 0.680851 (-8640 860);
PAINT MONO (-8640 860);
FORCEPROP 0 LASTPIN (-8650 950) $PN 3
J 0
(-8640 960);
DISPLAY 0.680851 (-8640 960);
PAINT MONO (-8640 960);
FORCEPROP 0 LASTPIN (-8850 1050) $PN 4
R 1
J 0
(-8860 1060);
DISPLAY 0.680851 (-8860 1060);
PAINT MONO (-8860 1060);
FORCEPROP 0 LASTPIN (-9050 950) $PN 5
J 2
(-9060 960);
DISPLAY 0.680851 (-9060 960);
PAINT MONO (-9060 960);
FORCEPROP 0 LASTPIN (-9050 850) $PN 6
J 2
(-9060 860);
DISPLAY 0.680851 (-9060 860);
PAINT MONO (-9060 860);
FORCEPROP 0 LASTPIN (-8950 650) $PN 7
R 1
J 2
(-8960 640);
DISPLAY 0.680851 (-8960 640);
PAINT MONO (-8960 640);
FORCEPROP 0 LASTPIN (-8850 650) $PN 8
R 1
J 2
(-8860 640);
DISPLAY 0.680851 (-8860 640);
PAINT MONO (-8860 640);
FORCEPROP 0 LASTPIN (-8750 650) $PN 9
R 1
J 2
(-8760 640);
DISPLAY 0.680851 (-8760 640);
PAINT MONO (-8760 640);
FORCEPROP 2 LAST PACK_TYPE TH
J 0
(-9000 1325);
DISPLAY 1.021277 (-9000 1325);
FORCEPROP 1 LAST MATERIAL EMPTY
J 0
(-9000 1180);
DISPLAY 0.723404 (-9000 1180);
PAINT GREEN (-9000 1180);
FORCEPROP 1 LAST NEEDS_NO_SIZE TRUE
J 0
(-8850 850);
DISPLAY 0.468085 (-8850 850);
PAINT GREEN (-8850 850);
DISPLAY INVISIBLE (-8850 850);
FORCEPROP 2 LAST CDS_LIB pure_quanta
J 0
(-8850 850);
DISPLAY INVISIBLE (-8850 850);
FORCEPROP 1 LAST PATH I25
J 0
(-8750 1160);
DISPLAY 0.723404 (-8750 1160);
PAINT GREEN (-8750 1160);
DISPLAY INVISIBLE (-8750 1160);
FORCEPROP 1 LAST PART_NUMBER GND_HOLE140
J 0
(-9000 1235);
DISPLAY 0.723404 (-9000 1235);
PAINT GREEN (-9000 1235);
DISPLAY INVISIBLE (-9000 1235);
FORCEADD HOLE..1
(-8250 2800);
FORCEPROP 1 LAST LOCATION H22
J 0
(-8375 3035);
DISPLAY 0.489362 (-8375 3035);
PAINT SKYBLUE (-8375 3035);
FORCEPROP 0 LAST $SEC 1
J 0
(-8375 3125);
DISPLAY 0.680851 (-8375 3125);
PAINT MONO (-8375 3125);
DISPLAY INVISIBLE (-8375 3125);
FORCEPROP 0 LAST CDS_SEC 1
J 0
(-8375 3125);
DISPLAY 0.680851 (-8375 3125);
DISPLAY INVISIBLE (-8375 3125);
FORCEPROP 0 LASTPIN (-8450 2825) $PN 1
J 2
(-8460 2835);
DISPLAY 0.489362 (-8460 2835);
PAINT MONO (-8460 2835);
FORCEPROP 2 LAST PACK_TYPE TH
J 0
(-8375 3075);
DISPLAY 0.489362 (-8375 3075);
PAINT SKYBLUE (-8375 3075);
FORCEPROP 1 LAST MATERIAL EMPTY
J 0
(-8375 2935);
DISPLAY 0.489362 (-8375 2935);
PAINT RED (-8375 2935);
FORCEPROP 2 LAST CDS_LIB pure_quanta
J 0
(-8250 2800);
DISPLAY INVISIBLE (-8250 2800);
FORCEPROP 1 LAST NEEDS_NO_SIZE TRUE
J 0
(-8250 2800);
DISPLAY 0.468085 (-8250 2800);
PAINT GREEN (-8250 2800);
DISPLAY INVISIBLE (-8250 2800);
FORCEPROP 1 LAST PATH I26
J 0
(-8200 2930);
DISPLAY 0.723404 (-8200 2930);
PAINT GREEN (-8200 2930);
DISPLAY INVISIBLE (-8200 2930);
FORCEPROP 1 LAST PART_NUMBER HOLE1226
J 0
(-8375 2980);
DISPLAY 0.489362 (-8375 2980);
PAINT SKYBLUE (-8375 2980);
DISPLAY INVISIBLE (-8375 2980);
FORCEADD HOLE..1
(-7700 2800);
FORCEPROP 1 LAST LOCATION H8028
J 0
(-7825 3035);
DISPLAY 0.489362 (-7825 3035);
PAINT SKYBLUE (-7825 3035);
FORCEPROP 0 LAST $SEC 1
J 0
(-7825 3125);
DISPLAY 0.680851 (-7825 3125);
PAINT MONO (-7825 3125);
DISPLAY INVISIBLE (-7825 3125);
FORCEPROP 0 LAST CDS_SEC 1
J 0
(-7825 3125);
DISPLAY 0.680851 (-7825 3125);
DISPLAY INVISIBLE (-7825 3125);
FORCEPROP 0 LASTPIN (-7900 2825) $PN 1
J 2
(-7910 2835);
DISPLAY 0.489362 (-7910 2835);
PAINT MONO (-7910 2835);
FORCEPROP 2 LAST PACK_TYPE TH
J 0
(-7825 3075);
DISPLAY 0.489362 (-7825 3075);
PAINT SKYBLUE (-7825 3075);
FORCEPROP 1 LAST MATERIAL EMPTY
J 0
(-7825 2935);
DISPLAY 0.489362 (-7825 2935);
PAINT RED (-7825 2935);
FORCEPROP 1 LAST NEEDS_NO_SIZE TRUE
J 0
(-7700 2800);
DISPLAY 0.468085 (-7700 2800);
PAINT GREEN (-7700 2800);
DISPLAY INVISIBLE (-7700 2800);
FORCEPROP 2 LAST CDS_LIB pure_quanta
J 0
(-7700 2800);
DISPLAY INVISIBLE (-7700 2800);
FORCEPROP 1 LAST PATH I27
J 0
(-7650 2930);
DISPLAY 0.723404 (-7650 2930);
PAINT GREEN (-7650 2930);
DISPLAY INVISIBLE (-7650 2930);
FORCEPROP 1 LAST PART_NUMBER HOLE1226
J 0
(-7825 2980);
DISPLAY 0.489362 (-7825 2980);
PAINT SKYBLUE (-7825 2980);
DISPLAY INVISIBLE (-7825 2980);
FORCEADD UNIVERSAL_GND..1
(-7900 2725);
FORCEPROP 3 LASTPIN (-7900 2775) SIG_NAME GND\g
J 0
(-7890 2785);
DISPLAY 0.659574 (-7890 2785);
PAINT MONO (-7890 2785);
DISPLAY INVISIBLE (-7890 2785);
FORCEPROP 2 LAST CDS_LIB pure_quanta_power
J 0
(-7900 2725);
DISPLAY INVISIBLE (-7900 2725);
FORCEPROP 1 LAST HDL_POWER GND
J 1
(-7875 2650);
DISPLAY 0.872340 (-7875 2650);
PAINT GREEN (-7875 2650);
DISPLAY INVISIBLE (-7875 2650);
FORCEPROP 1 LAST PATH I28
J 0
(-7825 2725);
DISPLAY 0.872340 (-7825 2725);
PAINT AQUA (-7825 2725);
DISPLAY INVISIBLE (-7825 2725);
FORCEADD UNIVERSAL_GND..1
(-8350 475);
FORCEPROP 3 LASTPIN (-8350 525) SIG_NAME GND\g
J 0
(-8340 535);
DISPLAY 0.659574 (-8340 535);
PAINT MONO (-8340 535);
DISPLAY INVISIBLE (-8340 535);
FORCEPROP 2 LAST CDS_LIB pure_quanta_power
J 0
(-8350 475);
DISPLAY INVISIBLE (-8350 475);
FORCEPROP 1 LAST HDL_POWER GND
J 1
(-8325 400);
DISPLAY 0.872340 (-8325 400);
PAINT GREEN (-8325 400);
DISPLAY INVISIBLE (-8325 400);
FORCEPROP 1 LAST PATH I29
J 0
(-8275 475);
DISPLAY 0.872340 (-8275 475);
PAINT AQUA (-8275 475);
DISPLAY INVISIBLE (-8275 475);
FORCEADD UNIVERSAL_GND..1
(-9075 2750);
FORCEPROP 3 LASTPIN (-9075 2800) SIG_NAME GND\g
J 0
(-9065 2810);
DISPLAY 0.659574 (-9065 2810);
PAINT MONO (-9065 2810);
DISPLAY INVISIBLE (-9065 2810);
FORCEPROP 2 LAST CDS_LIB pure_quanta_power
J 0
(-9075 2750);
DISPLAY INVISIBLE (-9075 2750);
FORCEPROP 1 LAST HDL_POWER GND
J 1
(-9050 2675);
DISPLAY 0.872340 (-9050 2675);
PAINT GREEN (-9050 2675);
DISPLAY INVISIBLE (-9050 2675);
FORCEPROP 1 LAST PATH I3
J 0
(-9000 2750);
DISPLAY 0.872340 (-9000 2750);
PAINT AQUA (-9000 2750);
DISPLAY INVISIBLE (-9000 2750);
FORCEADD GND_HOLE..1
(-8075 875);
FORCEPROP 1 LAST LOCATION H114
J 0
(-8225 1300);
DISPLAY 0.723404 (-8225 1300);
PAINT GREEN (-8225 1300);
FORCEPROP 0 LAST $SEC 1
J 0
(-8225 1400);
DISPLAY 0.680851 (-8225 1400);
PAINT MONO (-8225 1400);
DISPLAY INVISIBLE (-8225 1400);
FORCEPROP 0 LAST CDS_SEC 1
J 0
(-8225 1400);
DISPLAY 1.021277 (-8225 1400);
DISPLAY INVISIBLE (-8225 1400);
FORCEPROP 0 LASTPIN (-7875 875) $PN 2
J 0
(-7865 885);
DISPLAY 0.680851 (-7865 885);
PAINT MONO (-7865 885);
FORCEPROP 0 LASTPIN (-7875 975) $PN 3
J 0
(-7865 985);
DISPLAY 0.680851 (-7865 985);
PAINT MONO (-7865 985);
FORCEPROP 0 LASTPIN (-8075 1075) $PN 4
R 1
J 0
(-8085 1085);
DISPLAY 0.680851 (-8085 1085);
PAINT MONO (-8085 1085);
FORCEPROP 0 LASTPIN (-8275 975) $PN 5
J 2
(-8285 985);
DISPLAY 0.680851 (-8285 985);
PAINT MONO (-8285 985);
FORCEPROP 0 LASTPIN (-8275 875) $PN 6
J 2
(-8285 885);
DISPLAY 0.680851 (-8285 885);
PAINT MONO (-8285 885);
FORCEPROP 0 LASTPIN (-8175 675) $PN 7
R 1
J 2
(-8185 665);
DISPLAY 0.680851 (-8185 665);
PAINT MONO (-8185 665);
FORCEPROP 0 LASTPIN (-8075 675) $PN 8
R 1
J 2
(-8085 665);
DISPLAY 0.680851 (-8085 665);
PAINT MONO (-8085 665);
FORCEPROP 0 LASTPIN (-7975 675) $PN 9
R 1
J 2
(-7985 665);
DISPLAY 0.680851 (-7985 665);
PAINT MONO (-7985 665);
FORCEPROP 1 LAST MATERIAL EMPTY
J 0
(-8225 1205);
DISPLAY 0.723404 (-8225 1205);
PAINT GREEN (-8225 1205);
FORCEPROP 2 LAST PACK_TYPE TH
J 0
(-8225 1350);
DISPLAY 1.021277 (-8225 1350);
FORCEPROP 1 LAST NEEDS_NO_SIZE TRUE
J 0
(-8075 875);
DISPLAY 0.468085 (-8075 875);
PAINT GREEN (-8075 875);
DISPLAY INVISIBLE (-8075 875);
FORCEPROP 2 LAST CDS_LIB pure_quanta
J 0
(-8075 875);
DISPLAY INVISIBLE (-8075 875);
FORCEPROP 1 LAST PATH I30
J 0
(-7975 1185);
DISPLAY 0.723404 (-7975 1185);
PAINT GREEN (-7975 1185);
DISPLAY INVISIBLE (-7975 1185);
FORCEPROP 1 LAST PART_NUMBER GND_HOLE140
J 0
(-8225 1260);
DISPLAY 0.723404 (-8225 1260);
PAINT GREEN (-8225 1260);
DISPLAY INVISIBLE (-8225 1260);
FORCEADD HOLE..1
(-7150 2800);
FORCEPROP 1 LAST LOCATION H34
J 0
(-7275 3035);
DISPLAY 0.489362 (-7275 3035);
PAINT SKYBLUE (-7275 3035);
FORCEPROP 0 LAST $SEC 1
J 0
(-7275 3125);
DISPLAY 0.680851 (-7275 3125);
PAINT MONO (-7275 3125);
DISPLAY INVISIBLE (-7275 3125);
FORCEPROP 0 LAST CDS_SEC 1
J 0
(-7275 3125);
DISPLAY 0.680851 (-7275 3125);
DISPLAY INVISIBLE (-7275 3125);
FORCEPROP 0 LASTPIN (-7350 2825) $PN 1
J 2
(-7360 2835);
DISPLAY 0.489362 (-7360 2835);
PAINT MONO (-7360 2835);
FORCEPROP 1 LAST MATERIAL EMPTY
J 0
(-7275 2935);
DISPLAY 0.489362 (-7275 2935);
PAINT RED (-7275 2935);
FORCEPROP 2 LAST PACK_TYPE TH
J 0
(-7275 3075);
DISPLAY 0.489362 (-7275 3075);
PAINT SKYBLUE (-7275 3075);
FORCEPROP 1 LAST NEEDS_NO_SIZE TRUE
J 0
(-7150 2800);
DISPLAY 0.468085 (-7150 2800);
PAINT GREEN (-7150 2800);
DISPLAY INVISIBLE (-7150 2800);
FORCEPROP 2 LAST CDS_LIB pure_quanta
J 0
(-7150 2800);
DISPLAY INVISIBLE (-7150 2800);
FORCEPROP 1 LAST PATH I31
J 0
(-7100 2930);
DISPLAY 0.723404 (-7100 2930);
PAINT GREEN (-7100 2930);
DISPLAY INVISIBLE (-7100 2930);
FORCEPROP 1 LAST PART_NUMBER HOLE1226
J 0
(-7275 2980);
DISPLAY 0.489362 (-7275 2980);
PAINT SKYBLUE (-7275 2980);
DISPLAY INVISIBLE (-7275 2980);
FORCEADD UNIVERSAL_GND..1
(-7350 2725);
FORCEPROP 3 LASTPIN (-7350 2775) SIG_NAME GND\g
J 0
(-7340 2785);
DISPLAY 0.659574 (-7340 2785);
PAINT MONO (-7340 2785);
DISPLAY INVISIBLE (-7340 2785);
FORCEPROP 2 LAST CDS_LIB pure_quanta_power
J 0
(-7350 2725);
DISPLAY INVISIBLE (-7350 2725);
FORCEPROP 1 LAST HDL_POWER GND
J 1
(-7325 2650);
DISPLAY 0.872340 (-7325 2650);
PAINT GREEN (-7325 2650);
DISPLAY INVISIBLE (-7325 2650);
FORCEPROP 1 LAST PATH I32
J 0
(-7275 2725);
DISPLAY 0.872340 (-7275 2725);
PAINT AQUA (-7275 2725);
DISPLAY INVISIBLE (-7275 2725);
FORCEADD HOLE..1
(-6575 2800);
FORCEPROP 1 LAST LOCATION H38
J 0
(-6700 3035);
DISPLAY 0.489362 (-6700 3035);
PAINT SKYBLUE (-6700 3035);
FORCEPROP 0 LAST $SEC 1
J 0
(-6700 3125);
DISPLAY 0.680851 (-6700 3125);
PAINT MONO (-6700 3125);
DISPLAY INVISIBLE (-6700 3125);
FORCEPROP 0 LAST CDS_SEC 1
J 0
(-6700 3125);
DISPLAY 0.680851 (-6700 3125);
DISPLAY INVISIBLE (-6700 3125);
FORCEPROP 0 LASTPIN (-6775 2825) $PN 1
J 2
(-6785 2835);
DISPLAY 0.489362 (-6785 2835);
PAINT MONO (-6785 2835);
FORCEPROP 1 LAST MATERIAL EMPTY
J 0
(-6700 2935);
DISPLAY 0.489362 (-6700 2935);
PAINT RED (-6700 2935);
FORCEPROP 2 LAST PACK_TYPE TH
J 0
(-6700 3075);
DISPLAY 0.489362 (-6700 3075);
PAINT SKYBLUE (-6700 3075);
FORCEPROP 2 LAST CDS_LIB pure_quanta
J 0
(-6575 2800);
DISPLAY INVISIBLE (-6575 2800);
FORCEPROP 1 LAST NEEDS_NO_SIZE TRUE
J 0
(-6575 2800);
DISPLAY 0.468085 (-6575 2800);
PAINT GREEN (-6575 2800);
DISPLAY INVISIBLE (-6575 2800);
FORCEPROP 1 LAST PATH I33
J 0
(-6525 2930);
DISPLAY 0.723404 (-6525 2930);
PAINT GREEN (-6525 2930);
DISPLAY INVISIBLE (-6525 2930);
FORCEPROP 1 LAST PART_NUMBER HOLE1226
J 0
(-6700 2980);
DISPLAY 0.489362 (-6700 2980);
PAINT SKYBLUE (-6700 2980);
DISPLAY INVISIBLE (-6700 2980);
FORCEADD UNIVERSAL_GND..1
(-6775 2725);
FORCEPROP 3 LASTPIN (-6775 2775) SIG_NAME GND\g
J 0
(-6765 2785);
DISPLAY 0.659574 (-6765 2785);
PAINT MONO (-6765 2785);
DISPLAY INVISIBLE (-6765 2785);
FORCEPROP 2 LAST CDS_LIB pure_quanta_power
J 0
(-6775 2725);
DISPLAY INVISIBLE (-6775 2725);
FORCEPROP 1 LAST HDL_POWER GND
J 1
(-6750 2650);
DISPLAY 0.872340 (-6750 2650);
PAINT GREEN (-6750 2650);
DISPLAY INVISIBLE (-6750 2650);
FORCEPROP 1 LAST PATH I34
J 0
(-6700 2725);
DISPLAY 0.872340 (-6700 2725);
PAINT AQUA (-6700 2725);
DISPLAY INVISIBLE (-6700 2725);
FORCEADD UNIVERSAL_GND..1
(-7950 3325);
FORCEPROP 3 LASTPIN (-7950 3375) SIG_NAME GND\g
J 0
(-7940 3385);
DISPLAY 0.659574 (-7940 3385);
PAINT MONO (-7940 3385);
DISPLAY INVISIBLE (-7940 3385);
FORCEPROP 2 LAST CDS_LIB pure_quanta_power
J 0
(-7950 3325);
DISPLAY INVISIBLE (-7950 3325);
FORCEPROP 1 LAST HDL_POWER GND
J 1
(-7925 3250);
DISPLAY 0.872340 (-7925 3250);
PAINT GREEN (-7925 3250);
DISPLAY INVISIBLE (-7925 3250);
FORCEPROP 1 LAST PATH I35
J 0
(-7875 3325);
DISPLAY 0.872340 (-7875 3325);
PAINT AQUA (-7875 3325);
DISPLAY INVISIBLE (-7875 3325);
FORCEADD HOLE..1
(-7750 3400);
FORCEPROP 1 LAST LOCATION H33
J 0
(-7875 3635);
DISPLAY 0.489362 (-7875 3635);
PAINT SKYBLUE (-7875 3635);
FORCEPROP 0 LAST $SEC 1
J 0
(-7875 3725);
DISPLAY 0.680851 (-7875 3725);
PAINT MONO (-7875 3725);
DISPLAY INVISIBLE (-7875 3725);
FORCEPROP 0 LAST CDS_SEC 1
J 0
(-7875 3725);
DISPLAY 0.680851 (-7875 3725);
DISPLAY INVISIBLE (-7875 3725);
FORCEPROP 0 LASTPIN (-7950 3425) $PN 1
J 2
(-7960 3435);
DISPLAY 0.489362 (-7960 3435);
PAINT MONO (-7960 3435);
FORCEPROP 1 LAST MATERIAL EMPTY
J 0
(-7875 3535);
DISPLAY 0.489362 (-7875 3535);
PAINT RED (-7875 3535);
FORCEPROP 2 LAST PACK_TYPE TH
J 0
(-7875 3675);
DISPLAY 0.489362 (-7875 3675);
PAINT SKYBLUE (-7875 3675);
FORCEPROP 1 LAST NEEDS_NO_SIZE TRUE
J 0
(-7750 3400);
DISPLAY 0.468085 (-7750 3400);
PAINT GREEN (-7750 3400);
DISPLAY INVISIBLE (-7750 3400);
FORCEPROP 2 LAST CDS_LIB pure_quanta
J 0
(-7750 3400);
DISPLAY INVISIBLE (-7750 3400);
FORCEPROP 1 LAST PATH I36
J 0
(-7700 3530);
DISPLAY 0.723404 (-7700 3530);
PAINT GREEN (-7700 3530);
DISPLAY INVISIBLE (-7700 3530);
FORCEPROP 1 LAST PART_NUMBER HOLE1226
J 0
(-7875 3580);
DISPLAY 0.489362 (-7875 3580);
PAINT SKYBLUE (-7875 3580);
DISPLAY INVISIBLE (-7875 3580);
FORCEADD UNIVERSAL_GND..1
(-7375 3325);
FORCEPROP 3 LASTPIN (-7375 3375) SIG_NAME GND\g
J 0
(-7365 3385);
DISPLAY 0.659574 (-7365 3385);
PAINT MONO (-7365 3385);
DISPLAY INVISIBLE (-7365 3385);
FORCEPROP 2 LAST CDS_LIB pure_quanta_power
J 0
(-7375 3325);
DISPLAY INVISIBLE (-7375 3325);
FORCEPROP 1 LAST HDL_POWER GND
J 1
(-7350 3250);
DISPLAY 0.872340 (-7350 3250);
PAINT GREEN (-7350 3250);
DISPLAY INVISIBLE (-7350 3250);
FORCEPROP 1 LAST PATH I37
J 0
(-7300 3325);
DISPLAY 0.872340 (-7300 3325);
PAINT AQUA (-7300 3325);
DISPLAY INVISIBLE (-7300 3325);
FORCEADD HOLE..1
(-7175 3400);
FORCEPROP 1 LAST LOCATION H37
J 0
(-7300 3635);
DISPLAY 0.489362 (-7300 3635);
PAINT SKYBLUE (-7300 3635);
FORCEPROP 0 LAST $SEC 1
J 0
(-7300 3725);
DISPLAY 0.680851 (-7300 3725);
PAINT MONO (-7300 3725);
DISPLAY INVISIBLE (-7300 3725);
FORCEPROP 0 LAST CDS_SEC 1
J 0
(-7300 3725);
DISPLAY 0.680851 (-7300 3725);
DISPLAY INVISIBLE (-7300 3725);
FORCEPROP 0 LASTPIN (-7375 3425) $PN 1
J 2
(-7385 3435);
DISPLAY 0.489362 (-7385 3435);
PAINT MONO (-7385 3435);
FORCEPROP 1 LAST MATERIAL EMPTY
J 0
(-7300 3535);
DISPLAY 0.489362 (-7300 3535);
PAINT RED (-7300 3535);
FORCEPROP 2 LAST PACK_TYPE TH
J 0
(-7300 3675);
DISPLAY 0.489362 (-7300 3675);
PAINT SKYBLUE (-7300 3675);
FORCEPROP 1 LAST NEEDS_NO_SIZE TRUE
J 0
(-7175 3400);
DISPLAY 0.468085 (-7175 3400);
PAINT GREEN (-7175 3400);
DISPLAY INVISIBLE (-7175 3400);
FORCEPROP 2 LAST CDS_LIB pure_quanta
J 0
(-7175 3400);
DISPLAY INVISIBLE (-7175 3400);
FORCEPROP 1 LAST PATH I38
J 0
(-7125 3530);
DISPLAY 0.723404 (-7125 3530);
PAINT GREEN (-7125 3530);
DISPLAY INVISIBLE (-7125 3530);
FORCEPROP 1 LAST PART_NUMBER HOLE1226
J 0
(-7300 3580);
DISPLAY 0.489362 (-7300 3580);
PAINT SKYBLUE (-7300 3580);
DISPLAY INVISIBLE (-7300 3580);
FORCEADD UNIVERSAL_GND..1
(-6875 3325);
FORCEPROP 3 LASTPIN (-6875 3375) SIG_NAME GND\g
J 0
(-6865 3385);
DISPLAY 0.659574 (-6865 3385);
PAINT MONO (-6865 3385);
DISPLAY INVISIBLE (-6865 3385);
FORCEPROP 2 LAST CDS_LIB pure_quanta_power
J 0
(-6875 3325);
DISPLAY INVISIBLE (-6875 3325);
FORCEPROP 1 LAST HDL_POWER GND
J 1
(-6850 3250);
DISPLAY 0.872340 (-6850 3250);
PAINT GREEN (-6850 3250);
DISPLAY INVISIBLE (-6850 3250);
FORCEPROP 1 LAST PATH I39
J 0
(-6800 3325);
DISPLAY 0.872340 (-6800 3325);
PAINT AQUA (-6800 3325);
DISPLAY INVISIBLE (-6800 3325);
FORCEADD HOLE..1
(-8875 2825);
FORCEPROP 1 LAST LOCATION H53
J 0
(-9000 3060);
DISPLAY 0.489362 (-9000 3060);
PAINT SKYBLUE (-9000 3060);
FORCEPROP 0 LAST $SEC 1
J 0
(-9000 3150);
DISPLAY 0.680851 (-9000 3150);
PAINT MONO (-9000 3150);
DISPLAY INVISIBLE (-9000 3150);
FORCEPROP 0 LAST CDS_SEC 1
J 0
(-9000 3150);
DISPLAY 0.680851 (-9000 3150);
DISPLAY INVISIBLE (-9000 3150);
FORCEPROP 0 LASTPIN (-9075 2850) $PN 1
J 2
(-9085 2860);
DISPLAY 0.489362 (-9085 2860);
PAINT MONO (-9085 2860);
FORCEPROP 1 LAST MATERIAL EMPTY
J 0
(-9000 2960);
DISPLAY 0.489362 (-9000 2960);
PAINT RED (-9000 2960);
FORCEPROP 2 LAST PACK_TYPE TH
J 0
(-9000 3100);
DISPLAY 0.489362 (-9000 3100);
PAINT SKYBLUE (-9000 3100);
FORCEPROP 1 LAST NEEDS_NO_SIZE TRUE
J 0
(-8875 2825);
DISPLAY 0.468085 (-8875 2825);
PAINT GREEN (-8875 2825);
DISPLAY INVISIBLE (-8875 2825);
FORCEPROP 2 LAST CDS_LIB pure_quanta
J 0
(-8875 2825);
DISPLAY INVISIBLE (-8875 2825);
FORCEPROP 1 LAST PATH I4
J 0
(-8825 2955);
DISPLAY 0.723404 (-8825 2955);
PAINT GREEN (-8825 2955);
DISPLAY INVISIBLE (-8825 2955);
FORCEPROP 1 LAST PART_NUMBER HOLE1226
J 0
(-9000 3005);
DISPLAY 0.489362 (-9000 3005);
PAINT SKYBLUE (-9000 3005);
DISPLAY INVISIBLE (-9000 3005);
FORCEADD HOLE..1
(-6675 3400);
FORCEPROP 1 LAST LOCATION H43
J 0
(-6800 3635);
DISPLAY 0.489362 (-6800 3635);
PAINT SKYBLUE (-6800 3635);
FORCEPROP 0 LAST $SEC 1
J 0
(-6800 3725);
DISPLAY 0.680851 (-6800 3725);
PAINT MONO (-6800 3725);
DISPLAY INVISIBLE (-6800 3725);
FORCEPROP 0 LAST CDS_SEC 1
J 0
(-6800 3725);
DISPLAY 0.680851 (-6800 3725);
DISPLAY INVISIBLE (-6800 3725);
FORCEPROP 0 LASTPIN (-6875 3425) $PN 1
J 2
(-6885 3435);
DISPLAY 0.489362 (-6885 3435);
PAINT MONO (-6885 3435);
FORCEPROP 1 LAST MATERIAL EMPTY
J 0
(-6800 3535);
DISPLAY 0.489362 (-6800 3535);
PAINT RED (-6800 3535);
FORCEPROP 2 LAST PACK_TYPE TH
J 0
(-6800 3675);
DISPLAY 0.489362 (-6800 3675);
PAINT SKYBLUE (-6800 3675);
FORCEPROP 1 LAST NEEDS_NO_SIZE TRUE
J 0
(-6675 3400);
DISPLAY 0.468085 (-6675 3400);
PAINT GREEN (-6675 3400);
DISPLAY INVISIBLE (-6675 3400);
FORCEPROP 2 LAST CDS_LIB pure_quanta
J 0
(-6675 3400);
DISPLAY INVISIBLE (-6675 3400);
FORCEPROP 1 LAST PATH I40
J 0
(-6625 3530);
DISPLAY 0.723404 (-6625 3530);
PAINT GREEN (-6625 3530);
DISPLAY INVISIBLE (-6625 3530);
FORCEPROP 1 LAST PART_NUMBER HOLE1226
J 0
(-6800 3580);
DISPLAY 0.489362 (-6800 3580);
PAINT SKYBLUE (-6800 3580);
DISPLAY INVISIBLE (-6800 3580);
FORCEADD HOLE..1
(-6225 4275);
FORCEPROP 1 LAST LOCATION H27
J 0
(-6350 4510);
DISPLAY 0.723404 (-6350 4510);
PAINT GREEN (-6350 4510);
FORCEPROP 2 LAST $SEC 1
J 0
(-6350 4600);
DISPLAY 0.680851 (-6350 4600);
PAINT MONO (-6350 4600);
DISPLAY INVISIBLE (-6350 4600);
FORCEPROP 2 LAST CDS_SEC 1
J 0
(-6350 4600);
DISPLAY 1.021277 (-6350 4600);
DISPLAY INVISIBLE (-6350 4600);
FORCEPROP 2 LASTPIN (-6425 4300) $PN 1
J 2
(-6435 4310);
DISPLAY 0.808511 (-6435 4310);
FORCEPROP 1 LAST MATERIAL EMPTY
J 0
(-6350 4410);
DISPLAY 0.723404 (-6350 4410);
PAINT GREEN (-6350 4410);
FORCEPROP 2 LAST PACK_TYPE TH
J 0
(-6350 4550);
DISPLAY 1.021277 (-6350 4550);
FORCEPROP 1 LAST NEEDS_NO_SIZE TRUE
J 0
(-6225 4275);
DISPLAY 0.468085 (-6225 4275);
PAINT GREEN (-6225 4275);
DISPLAY INVISIBLE (-6225 4275);
FORCEPROP 2 LAST CDS_LIB pure_quanta
J 0
(-6225 4275);
PAINT MONO (-6225 4275);
DISPLAY INVISIBLE (-6225 4275);
FORCEPROP 1 LAST PATH I41
J 0
(-6175 4405);
DISPLAY 0.723404 (-6175 4405);
PAINT GREEN (-6175 4405);
DISPLAY INVISIBLE (-6175 4405);
FORCEPROP 1 LAST PART_NUMBER DUMMY50
J 0
(-6350 4455);
DISPLAY 0.723404 (-6350 4455);
PAINT GREEN (-6350 4455);
DISPLAY INVISIBLE (-6350 4455);
FORCEADD UNIVERSAL_GND..1
(-5700 450);
FORCEPROP 3 LASTPIN (-5700 500) SIG_NAME GND\g
J 0
(-5690 510);
DISPLAY 0.659574 (-5690 510);
PAINT MONO (-5690 510);
DISPLAY INVISIBLE (-5690 510);
FORCEPROP 2 LAST CDS_LIB pure_quanta_power
J 0
(-5700 450);
DISPLAY INVISIBLE (-5700 450);
FORCEPROP 1 LAST HDL_POWER GND
J 1
(-5675 375);
DISPLAY 0.872340 (-5675 375);
PAINT GREEN (-5675 375);
DISPLAY INVISIBLE (-5675 375);
FORCEPROP 1 LAST PATH I42
J 0
(-5625 450);
DISPLAY 0.872340 (-5625 450);
PAINT AQUA (-5625 450);
DISPLAY INVISIBLE (-5625 450);
FORCEADD GND_HOLE..1
(-5425 850);
FORCEPROP 1 LAST LOCATION H115
J 0
(-5575 1275);
DISPLAY 0.723404 (-5575 1275);
PAINT GREEN (-5575 1275);
FORCEPROP 0 LAST $SEC 1
J 0
(-5575 1375);
DISPLAY 0.680851 (-5575 1375);
PAINT MONO (-5575 1375);
DISPLAY INVISIBLE (-5575 1375);
FORCEPROP 0 LAST CDS_SEC 1
J 0
(-5575 1375);
DISPLAY 1.021277 (-5575 1375);
DISPLAY INVISIBLE (-5575 1375);
FORCEPROP 0 LASTPIN (-5225 850) $PN 2
J 0
(-5215 860);
DISPLAY 0.680851 (-5215 860);
PAINT MONO (-5215 860);
FORCEPROP 0 LASTPIN (-5225 950) $PN 3
J 0
(-5215 960);
DISPLAY 0.680851 (-5215 960);
PAINT MONO (-5215 960);
FORCEPROP 0 LASTPIN (-5425 1050) $PN 4
R 1
J 0
(-5435 1060);
DISPLAY 0.680851 (-5435 1060);
PAINT MONO (-5435 1060);
FORCEPROP 0 LASTPIN (-5625 950) $PN 5
J 2
(-5635 960);
DISPLAY 0.680851 (-5635 960);
PAINT MONO (-5635 960);
FORCEPROP 0 LASTPIN (-5625 850) $PN 6
J 2
(-5635 860);
DISPLAY 0.680851 (-5635 860);
PAINT MONO (-5635 860);
FORCEPROP 0 LASTPIN (-5525 650) $PN 7
R 1
J 2
(-5535 640);
DISPLAY 0.680851 (-5535 640);
PAINT MONO (-5535 640);
FORCEPROP 0 LASTPIN (-5425 650) $PN 8
R 1
J 2
(-5435 640);
DISPLAY 0.680851 (-5435 640);
PAINT MONO (-5435 640);
FORCEPROP 0 LASTPIN (-5325 650) $PN 9
R 1
J 2
(-5335 640);
DISPLAY 0.680851 (-5335 640);
PAINT MONO (-5335 640);
FORCEPROP 1 LAST MATERIAL EMPTY
J 0
(-5575 1180);
DISPLAY 0.723404 (-5575 1180);
PAINT GREEN (-5575 1180);
FORCEPROP 2 LAST PACK_TYPE TH
J 0
(-5575 1325);
DISPLAY 1.021277 (-5575 1325);
FORCEPROP 1 LAST NEEDS_NO_SIZE TRUE
J 0
(-5425 850);
DISPLAY 0.468085 (-5425 850);
PAINT GREEN (-5425 850);
DISPLAY INVISIBLE (-5425 850);
FORCEPROP 2 LAST CDS_LIB pure_quanta
J 0
(-5425 850);
DISPLAY INVISIBLE (-5425 850);
FORCEPROP 1 LAST PATH I43
J 0
(-5325 1160);
DISPLAY 0.723404 (-5325 1160);
PAINT GREEN (-5325 1160);
DISPLAY INVISIBLE (-5325 1160);
FORCEPROP 1 LAST PART_NUMBER GND_HOLE514
J 0
(-5575 1235);
DISPLAY 0.723404 (-5575 1235);
PAINT GREEN (-5575 1235);
DISPLAY INVISIBLE (-5575 1235);
FORCEADD UNIVERSAL_GND..1
(-6275 2725);
FORCEPROP 3 LASTPIN (-6275 2775) SIG_NAME GND\g
J 0
(-6265 2785);
DISPLAY 0.659574 (-6265 2785);
PAINT MONO (-6265 2785);
DISPLAY INVISIBLE (-6265 2785);
FORCEPROP 2 LAST CDS_LIB pure_quanta_power
J 0
(-6275 2725);
DISPLAY INVISIBLE (-6275 2725);
FORCEPROP 1 LAST HDL_POWER GND
J 1
(-6250 2650);
DISPLAY 0.872340 (-6250 2650);
PAINT GREEN (-6250 2650);
DISPLAY INVISIBLE (-6250 2650);
FORCEPROP 1 LAST PATH I44
J 0
(-6200 2725);
DISPLAY 0.872340 (-6200 2725);
PAINT AQUA (-6200 2725);
DISPLAY INVISIBLE (-6200 2725);
FORCEADD HOLE..1
(-6075 2800);
FORCEPROP 1 LAST LOCATION H44
J 0
(-6200 3035);
DISPLAY 0.489362 (-6200 3035);
PAINT SKYBLUE (-6200 3035);
FORCEPROP 0 LAST $SEC 1
J 0
(-6200 3125);
DISPLAY 0.680851 (-6200 3125);
PAINT MONO (-6200 3125);
DISPLAY INVISIBLE (-6200 3125);
FORCEPROP 0 LAST CDS_SEC 1
J 0
(-6200 3125);
DISPLAY 0.680851 (-6200 3125);
DISPLAY INVISIBLE (-6200 3125);
FORCEPROP 0 LASTPIN (-6275 2825) $PN 1
J 2
(-6285 2835);
DISPLAY 0.489362 (-6285 2835);
PAINT MONO (-6285 2835);
FORCEPROP 1 LAST MATERIAL EMPTY
J 0
(-6200 2935);
DISPLAY 0.489362 (-6200 2935);
PAINT RED (-6200 2935);
FORCEPROP 2 LAST PACK_TYPE TH
J 0
(-6200 3075);
DISPLAY 0.489362 (-6200 3075);
PAINT SKYBLUE (-6200 3075);
FORCEPROP 1 LAST NEEDS_NO_SIZE TRUE
J 0
(-6075 2800);
DISPLAY 0.468085 (-6075 2800);
PAINT GREEN (-6075 2800);
DISPLAY INVISIBLE (-6075 2800);
FORCEPROP 2 LAST CDS_LIB pure_quanta
J 0
(-6075 2800);
DISPLAY INVISIBLE (-6075 2800);
FORCEPROP 1 LAST PATH I45
J 0
(-6025 2930);
DISPLAY 0.723404 (-6025 2930);
PAINT GREEN (-6025 2930);
DISPLAY INVISIBLE (-6025 2930);
FORCEPROP 1 LAST PART_NUMBER HOLE1226
J 0
(-6200 2980);
DISPLAY 0.489362 (-6200 2980);
PAINT SKYBLUE (-6200 2980);
DISPLAY INVISIBLE (-6200 2980);
FORCEADD HOLE..1
(-6125 3400);
FORCEPROP 1 LAST LOCATION H49
J 0
(-6250 3635);
DISPLAY 0.489362 (-6250 3635);
PAINT SKYBLUE (-6250 3635);
FORCEPROP 0 LAST $SEC 1
J 0
(-6250 3725);
DISPLAY 0.680851 (-6250 3725);
PAINT MONO (-6250 3725);
DISPLAY INVISIBLE (-6250 3725);
FORCEPROP 0 LAST CDS_SEC 1
J 0
(-6250 3725);
DISPLAY 0.680851 (-6250 3725);
DISPLAY INVISIBLE (-6250 3725);
FORCEPROP 0 LASTPIN (-6325 3425) $PN 1
J 2
(-6335 3435);
DISPLAY 0.489362 (-6335 3435);
PAINT MONO (-6335 3435);
FORCEPROP 2 LAST PACK_TYPE TH
J 0
(-6250 3675);
DISPLAY 0.489362 (-6250 3675);
PAINT SKYBLUE (-6250 3675);
FORCEPROP 1 LAST MATERIAL EMPTY
J 0
(-6250 3535);
DISPLAY 0.489362 (-6250 3535);
PAINT RED (-6250 3535);
FORCEPROP 1 LAST NEEDS_NO_SIZE TRUE
J 0
(-6125 3400);
DISPLAY 0.468085 (-6125 3400);
PAINT GREEN (-6125 3400);
DISPLAY INVISIBLE (-6125 3400);
FORCEPROP 2 LAST CDS_LIB pure_quanta
J 0
(-6125 3400);
DISPLAY INVISIBLE (-6125 3400);
FORCEPROP 1 LAST PATH I46
J 0
(-6075 3530);
DISPLAY 0.723404 (-6075 3530);
PAINT GREEN (-6075 3530);
DISPLAY INVISIBLE (-6075 3530);
FORCEPROP 1 LAST PART_NUMBER HOLE1226
J 0
(-6250 3580);
DISPLAY 0.489362 (-6250 3580);
PAINT SKYBLUE (-6250 3580);
DISPLAY INVISIBLE (-6250 3580);
FORCEADD UNIVERSAL_GND..1
(-6325 3325);
FORCEPROP 3 LASTPIN (-6325 3375) SIG_NAME GND\g
J 0
(-6315 3385);
DISPLAY 0.659574 (-6315 3385);
PAINT MONO (-6315 3385);
DISPLAY INVISIBLE (-6315 3385);
FORCEPROP 2 LAST CDS_LIB pure_quanta_power
J 0
(-6325 3325);
DISPLAY INVISIBLE (-6325 3325);
FORCEPROP 1 LAST HDL_POWER GND
J 1
(-6300 3250);
DISPLAY 0.872340 (-6300 3250);
PAINT GREEN (-6300 3250);
DISPLAY INVISIBLE (-6300 3250);
FORCEPROP 1 LAST PATH I47
J 0
(-6250 3325);
DISPLAY 0.872340 (-6250 3325);
PAINT AQUA (-6250 3325);
DISPLAY INVISIBLE (-6250 3325);
FORCEADD UNIVERSAL_GND..1
(-5800 3325);
FORCEPROP 3 LASTPIN (-5800 3375) SIG_NAME GND\g
J 0
(-5790 3385);
DISPLAY 0.659574 (-5790 3385);
PAINT MONO (-5790 3385);
DISPLAY INVISIBLE (-5790 3385);
FORCEPROP 2 LAST CDS_LIB pure_quanta_power
J 0
(-5800 3325);
DISPLAY INVISIBLE (-5800 3325);
FORCEPROP 1 LAST HDL_POWER GND
J 1
(-5775 3250);
DISPLAY 0.872340 (-5775 3250);
PAINT GREEN (-5775 3250);
DISPLAY INVISIBLE (-5775 3250);
FORCEPROP 1 LAST PATH I48
J 0
(-5725 3325);
DISPLAY 0.872340 (-5725 3325);
PAINT AQUA (-5725 3325);
DISPLAY INVISIBLE (-5725 3325);
FORCEADD HOLE..1
(-5600 3400);
FORCEPROP 1 LAST LOCATION H50
J 0
(-5725 3635);
DISPLAY 0.489362 (-5725 3635);
PAINT SKYBLUE (-5725 3635);
FORCEPROP 0 LAST $SEC 1
J 0
(-5725 3725);
DISPLAY 0.680851 (-5725 3725);
PAINT MONO (-5725 3725);
DISPLAY INVISIBLE (-5725 3725);
FORCEPROP 0 LAST CDS_SEC 1
J 0
(-5725 3725);
DISPLAY 0.680851 (-5725 3725);
DISPLAY INVISIBLE (-5725 3725);
FORCEPROP 0 LASTPIN (-5800 3425) $PN 1
J 2
(-5810 3435);
DISPLAY 0.489362 (-5810 3435);
PAINT MONO (-5810 3435);
FORCEPROP 1 LAST MATERIAL EMPTY
J 0
(-5725 3535);
DISPLAY 0.489362 (-5725 3535);
PAINT RED (-5725 3535);
FORCEPROP 2 LAST PACK_TYPE TH
J 0
(-5725 3675);
DISPLAY 0.489362 (-5725 3675);
PAINT SKYBLUE (-5725 3675);
FORCEPROP 1 LAST NEEDS_NO_SIZE TRUE
J 0
(-5600 3400);
DISPLAY 0.468085 (-5600 3400);
PAINT GREEN (-5600 3400);
DISPLAY INVISIBLE (-5600 3400);
FORCEPROP 2 LAST CDS_LIB pure_quanta
J 0
(-5600 3400);
DISPLAY INVISIBLE (-5600 3400);
FORCEPROP 1 LAST PATH I49
J 0
(-5550 3530);
DISPLAY 0.723404 (-5550 3530);
PAINT GREEN (-5550 3530);
DISPLAY INVISIBLE (-5550 3530);
FORCEPROP 1 LAST PART_NUMBER HOLE1226
J 0
(-5725 3580);
DISPLAY 0.489362 (-5725 3580);
PAINT SKYBLUE (-5725 3580);
DISPLAY INVISIBLE (-5725 3580);
FORCEADD HOLE..1
(-8850 3400);
FORCEPROP 1 LAST LOCATION H21
J 0
(-8975 3635);
DISPLAY 0.489362 (-8975 3635);
PAINT SKYBLUE (-8975 3635);
FORCEPROP 0 LAST $SEC 1
J 0
(-8975 3725);
DISPLAY 0.680851 (-8975 3725);
PAINT MONO (-8975 3725);
DISPLAY INVISIBLE (-8975 3725);
FORCEPROP 0 LAST CDS_SEC 1
J 0
(-8975 3725);
DISPLAY 0.680851 (-8975 3725);
DISPLAY INVISIBLE (-8975 3725);
FORCEPROP 0 LASTPIN (-9050 3425) $PN 1
J 2
(-9060 3435);
DISPLAY 0.489362 (-9060 3435);
PAINT MONO (-9060 3435);
FORCEPROP 2 LAST PACK_TYPE TH
J 0
(-8975 3675);
DISPLAY 0.489362 (-8975 3675);
PAINT SKYBLUE (-8975 3675);
FORCEPROP 1 LAST MATERIAL EMPTY
J 0
(-8975 3535);
DISPLAY 0.489362 (-8975 3535);
PAINT RED (-8975 3535);
FORCEPROP 2 LAST CDS_LIB pure_quanta
J 0
(-8850 3400);
DISPLAY INVISIBLE (-8850 3400);
FORCEPROP 1 LAST NEEDS_NO_SIZE TRUE
J 0
(-8850 3400);
DISPLAY 0.468085 (-8850 3400);
PAINT GREEN (-8850 3400);
DISPLAY INVISIBLE (-8850 3400);
FORCEPROP 1 LAST PATH I5
J 0
(-8800 3530);
DISPLAY 0.723404 (-8800 3530);
PAINT GREEN (-8800 3530);
DISPLAY INVISIBLE (-8800 3530);
FORCEPROP 1 LAST PART_NUMBER HOLE1226
J 0
(-8975 3580);
DISPLAY 0.489362 (-8975 3580);
PAINT SKYBLUE (-8975 3580);
DISPLAY INVISIBLE (-8975 3580);
FORCEADD HOLE..1
(-5725 4275);
FORCEPROP 1 LAST LOCATION H28
J 0
(-5850 4510);
DISPLAY 0.723404 (-5850 4510);
PAINT GREEN (-5850 4510);
FORCEPROP 2 LAST $SEC 1
J 0
(-5850 4600);
DISPLAY 0.680851 (-5850 4600);
PAINT MONO (-5850 4600);
DISPLAY INVISIBLE (-5850 4600);
FORCEPROP 2 LAST CDS_SEC 1
J 0
(-5850 4600);
DISPLAY 1.021277 (-5850 4600);
DISPLAY INVISIBLE (-5850 4600);
FORCEPROP 2 LASTPIN (-5925 4300) $PN 1
J 2
(-5935 4310);
DISPLAY 0.808511 (-5935 4310);
FORCEPROP 1 LAST MATERIAL EMPTY
J 0
(-5850 4410);
DISPLAY 0.723404 (-5850 4410);
PAINT GREEN (-5850 4410);
FORCEPROP 2 LAST PACK_TYPE TH
J 0
(-5850 4550);
DISPLAY 1.021277 (-5850 4550);
FORCEPROP 1 LAST NEEDS_NO_SIZE TRUE
J 0
(-5725 4275);
DISPLAY 0.468085 (-5725 4275);
PAINT GREEN (-5725 4275);
DISPLAY INVISIBLE (-5725 4275);
FORCEPROP 2 LAST CDS_LIB pure_quanta
J 0
(-5725 4275);
PAINT MONO (-5725 4275);
DISPLAY INVISIBLE (-5725 4275);
FORCEPROP 1 LAST PATH I50
J 0
(-5675 4405);
DISPLAY 0.723404 (-5675 4405);
PAINT GREEN (-5675 4405);
DISPLAY INVISIBLE (-5675 4405);
FORCEPROP 1 LAST PART_NUMBER DUMMY50
J 0
(-5850 4455);
DISPLAY 0.723404 (-5850 4455);
PAINT GREEN (-5850 4455);
DISPLAY INVISIBLE (-5850 4455);
FORCEADD HOLE..1
(-5200 4275);
FORCEPROP 1 LAST LOCATION H29
J 0
(-5325 4510);
DISPLAY 0.723404 (-5325 4510);
PAINT GREEN (-5325 4510);
FORCEPROP 2 LAST $SEC 1
J 0
(-5325 4600);
DISPLAY 0.680851 (-5325 4600);
PAINT MONO (-5325 4600);
DISPLAY INVISIBLE (-5325 4600);
FORCEPROP 2 LAST CDS_SEC 1
J 0
(-5325 4600);
DISPLAY 1.021277 (-5325 4600);
DISPLAY INVISIBLE (-5325 4600);
FORCEPROP 2 LASTPIN (-5400 4300) $PN 1
J 2
(-5410 4310);
DISPLAY 0.808511 (-5410 4310);
FORCEPROP 1 LAST MATERIAL EMPTY
J 0
(-5325 4410);
DISPLAY 0.723404 (-5325 4410);
PAINT GREEN (-5325 4410);
FORCEPROP 2 LAST PACK_TYPE TH
J 0
(-5325 4550);
DISPLAY 1.021277 (-5325 4550);
FORCEPROP 2 LAST CDS_LIB pure_quanta
J 0
(-5200 4275);
PAINT MONO (-5200 4275);
DISPLAY INVISIBLE (-5200 4275);
FORCEPROP 1 LAST NEEDS_NO_SIZE TRUE
J 0
(-5200 4275);
DISPLAY 0.468085 (-5200 4275);
PAINT GREEN (-5200 4275);
DISPLAY INVISIBLE (-5200 4275);
FORCEPROP 1 LAST PATH I51
J 0
(-5150 4405);
DISPLAY 0.723404 (-5150 4405);
PAINT GREEN (-5150 4405);
DISPLAY INVISIBLE (-5150 4405);
FORCEPROP 1 LAST PART_NUMBER DUMMY50
J 0
(-5325 4455);
DISPLAY 0.723404 (-5325 4455);
PAINT GREEN (-5325 4455);
DISPLAY INVISIBLE (-5325 4455);
FORCEADD HOLE..1
(-5025 3400);
FORCEPROP 1 LAST LOCATION H54
J 0
(-5150 3635);
DISPLAY 0.489362 (-5150 3635);
PAINT SKYBLUE (-5150 3635);
FORCEPROP 0 LAST $SEC 1
J 0
(-5150 3725);
DISPLAY 0.680851 (-5150 3725);
PAINT MONO (-5150 3725);
DISPLAY INVISIBLE (-5150 3725);
FORCEPROP 0 LAST CDS_SEC 1
J 0
(-5150 3725);
DISPLAY 0.680851 (-5150 3725);
DISPLAY INVISIBLE (-5150 3725);
FORCEPROP 0 LASTPIN (-5225 3425) $PN 1
J 2
(-5235 3435);
DISPLAY 0.489362 (-5235 3435);
PAINT MONO (-5235 3435);
FORCEPROP 1 LAST MATERIAL EMPTY
J 0
(-5150 3535);
DISPLAY 0.489362 (-5150 3535);
PAINT RED (-5150 3535);
FORCEPROP 2 LAST PACK_TYPE TH
J 0
(-5150 3675);
DISPLAY 0.489362 (-5150 3675);
PAINT SKYBLUE (-5150 3675);
FORCEPROP 2 LAST CDS_LIB pure_quanta
J 0
(-5025 3400);
DISPLAY INVISIBLE (-5025 3400);
FORCEPROP 1 LAST NEEDS_NO_SIZE TRUE
J 0
(-5025 3400);
DISPLAY 0.468085 (-5025 3400);
PAINT GREEN (-5025 3400);
DISPLAY INVISIBLE (-5025 3400);
FORCEPROP 1 LAST PATH I52
J 0
(-4975 3530);
DISPLAY 0.723404 (-4975 3530);
PAINT GREEN (-4975 3530);
DISPLAY INVISIBLE (-4975 3530);
FORCEPROP 1 LAST PART_NUMBER HOLE1226
J 0
(-5150 3580);
DISPLAY 0.489362 (-5150 3580);
PAINT SKYBLUE (-5150 3580);
DISPLAY INVISIBLE (-5150 3580);
FORCEADD UNIVERSAL_GND..1
(-5225 3325);
FORCEPROP 3 LASTPIN (-5225 3375) SIG_NAME GND\g
J 0
(-5215 3385);
DISPLAY 0.659574 (-5215 3385);
PAINT MONO (-5215 3385);
DISPLAY INVISIBLE (-5215 3385);
FORCEPROP 2 LAST CDS_LIB pure_quanta_power
J 0
(-5225 3325);
DISPLAY INVISIBLE (-5225 3325);
FORCEPROP 1 LAST HDL_POWER GND
J 1
(-5200 3250);
DISPLAY 0.872340 (-5200 3250);
PAINT GREEN (-5200 3250);
DISPLAY INVISIBLE (-5200 3250);
FORCEPROP 1 LAST PATH I53
J 0
(-5150 3325);
DISPLAY 0.872340 (-5150 3325);
PAINT AQUA (-5150 3325);
DISPLAY INVISIBLE (-5150 3325);
FORCEADD UNIVERSAL_GND..1
(-5775 2700);
FORCEPROP 3 LASTPIN (-5775 2750) SIG_NAME GND\g
J 0
(-5765 2760);
DISPLAY 0.659574 (-5765 2760);
PAINT MONO (-5765 2760);
DISPLAY INVISIBLE (-5765 2760);
FORCEPROP 2 LAST CDS_LIB pure_quanta_power
J 0
(-5775 2700);
DISPLAY INVISIBLE (-5775 2700);
FORCEPROP 1 LAST HDL_POWER GND
J 1
(-5750 2625);
DISPLAY 0.872340 (-5750 2625);
PAINT GREEN (-5750 2625);
DISPLAY INVISIBLE (-5750 2625);
FORCEPROP 1 LAST PATH I54
J 0
(-5700 2700);
DISPLAY 0.872340 (-5700 2700);
PAINT AQUA (-5700 2700);
DISPLAY INVISIBLE (-5700 2700);
FORCEADD HOLE..1
(-5575 2775);
FORCEPROP 1 LAST LOCATION H13
J 0
(-5700 3010);
DISPLAY 0.489362 (-5700 3010);
PAINT SKYBLUE (-5700 3010);
FORCEPROP 0 LAST $SEC 1
J 0
(-5700 3075);
DISPLAY 0.680851 (-5700 3075);
PAINT MONO (-5700 3075);
DISPLAY INVISIBLE (-5700 3075);
FORCEPROP 0 LAST CDS_SEC 1
J 0
(-5700 3075);
DISPLAY 0.680851 (-5700 3075);
DISPLAY INVISIBLE (-5700 3075);
FORCEPROP 0 LASTPIN (-5775 2800) $PN 1
J 2
(-5785 2810);
DISPLAY 0.489362 (-5785 2810);
PAINT MONO (-5785 2810);
FORCEPROP 1 LAST MATERIAL EMPTY
J 0
(-5700 2910);
DISPLAY 0.489362 (-5700 2910);
PAINT RED (-5700 2910);
FORCEPROP 2 LAST PACK_TYPE TH
J 0
(-5700 3050);
DISPLAY 0.489362 (-5700 3050);
PAINT SKYBLUE (-5700 3050);
FORCEPROP 2 LAST CDS_LIB pure_quanta
J 0
(-5575 2775);
DISPLAY INVISIBLE (-5575 2775);
FORCEPROP 1 LAST NEEDS_NO_SIZE TRUE
J 0
(-5575 2775);
DISPLAY 0.468085 (-5575 2775);
PAINT GREEN (-5575 2775);
DISPLAY INVISIBLE (-5575 2775);
FORCEPROP 1 LAST PATH I55
J 0
(-5525 2905);
DISPLAY 0.723404 (-5525 2905);
PAINT GREEN (-5525 2905);
DISPLAY INVISIBLE (-5525 2905);
FORCEPROP 1 LAST PART_NUMBER HOLE1226
J 0
(-5700 2955);
DISPLAY 0.489362 (-5700 2955);
PAINT SKYBLUE (-5700 2955);
DISPLAY INVISIBLE (-5700 2955);
FORCEADD HOLE..1
(-4700 4275);
FORCEPROP 1 LAST LOCATION H30
J 0
(-4825 4510);
DISPLAY 0.723404 (-4825 4510);
PAINT GREEN (-4825 4510);
FORCEPROP 2 LAST $SEC 1
J 0
(-4825 4600);
DISPLAY 0.680851 (-4825 4600);
PAINT MONO (-4825 4600);
DISPLAY INVISIBLE (-4825 4600);
FORCEPROP 2 LAST CDS_SEC 1
J 0
(-4825 4600);
DISPLAY 1.021277 (-4825 4600);
DISPLAY INVISIBLE (-4825 4600);
FORCEPROP 2 LASTPIN (-4900 4300) $PN 1
J 2
(-4910 4310);
DISPLAY 0.808511 (-4910 4310);
FORCEPROP 1 LAST MATERIAL EMPTY
J 0
(-4825 4410);
DISPLAY 0.723404 (-4825 4410);
PAINT GREEN (-4825 4410);
FORCEPROP 2 LAST PACK_TYPE TH
J 0
(-4825 4550);
DISPLAY 1.021277 (-4825 4550);
FORCEPROP 2 LAST CDS_LIB pure_quanta
J 0
(-4700 4275);
PAINT MONO (-4700 4275);
DISPLAY INVISIBLE (-4700 4275);
FORCEPROP 1 LAST NEEDS_NO_SIZE TRUE
J 0
(-4700 4275);
DISPLAY 0.468085 (-4700 4275);
PAINT GREEN (-4700 4275);
DISPLAY INVISIBLE (-4700 4275);
FORCEPROP 1 LAST PATH I56
J 0
(-4650 4405);
DISPLAY 0.723404 (-4650 4405);
PAINT GREEN (-4650 4405);
DISPLAY INVISIBLE (-4650 4405);
FORCEPROP 1 LAST PART_NUMBER DUMMY50
J 0
(-4825 4455);
DISPLAY 0.723404 (-4825 4455);
PAINT GREEN (-4825 4455);
DISPLAY INVISIBLE (-4825 4455);
FORCEADD UNIVERSAL_GND..1
(-9050 3325);
FORCEPROP 3 LASTPIN (-9050 3375) SIG_NAME GND\g
J 0
(-9040 3385);
DISPLAY 0.659574 (-9040 3385);
PAINT MONO (-9040 3385);
DISPLAY INVISIBLE (-9040 3385);
FORCEPROP 2 LAST CDS_LIB pure_quanta_power
J 0
(-9050 3325);
DISPLAY INVISIBLE (-9050 3325);
FORCEPROP 1 LAST HDL_POWER GND
J 1
(-9025 3250);
DISPLAY 0.872340 (-9025 3250);
PAINT GREEN (-9025 3250);
DISPLAY INVISIBLE (-9025 3250);
FORCEPROP 1 LAST PATH I6
J 0
(-8975 3325);
DISPLAY 0.872340 (-8975 3325);
PAINT AQUA (-8975 3325);
DISPLAY INVISIBLE (-8975 3325);
FORCEADD HOLE..1
(-8300 3400);
FORCEPROP 1 LAST LOCATION H8027
J 0
(-8425 3635);
DISPLAY 0.489362 (-8425 3635);
PAINT SKYBLUE (-8425 3635);
FORCEPROP 0 LAST $SEC 1
J 0
(-8425 3725);
DISPLAY 0.680851 (-8425 3725);
PAINT MONO (-8425 3725);
DISPLAY INVISIBLE (-8425 3725);
FORCEPROP 0 LAST CDS_SEC 1
J 0
(-8425 3725);
DISPLAY 0.680851 (-8425 3725);
DISPLAY INVISIBLE (-8425 3725);
FORCEPROP 0 LASTPIN (-8500 3425) $PN 1
J 2
(-8510 3435);
DISPLAY 0.489362 (-8510 3435);
PAINT MONO (-8510 3435);
FORCEPROP 2 LAST PACK_TYPE TH
J 0
(-8425 3675);
DISPLAY 0.489362 (-8425 3675);
PAINT SKYBLUE (-8425 3675);
FORCEPROP 1 LAST MATERIAL EMPTY
J 0
(-8425 3535);
DISPLAY 0.489362 (-8425 3535);
PAINT RED (-8425 3535);
FORCEPROP 1 LAST NEEDS_NO_SIZE TRUE
J 0
(-8300 3400);
DISPLAY 0.468085 (-8300 3400);
PAINT GREEN (-8300 3400);
DISPLAY INVISIBLE (-8300 3400);
FORCEPROP 2 LAST CDS_LIB pure_quanta
J 0
(-8300 3400);
DISPLAY INVISIBLE (-8300 3400);
FORCEPROP 1 LAST PATH I7
J 0
(-8250 3530);
DISPLAY 0.723404 (-8250 3530);
PAINT GREEN (-8250 3530);
DISPLAY INVISIBLE (-8250 3530);
FORCEPROP 1 LAST PART_NUMBER HOLE1226
J 0
(-8425 3580);
DISPLAY 0.489362 (-8425 3580);
PAINT SKYBLUE (-8425 3580);
DISPLAY INVISIBLE (-8425 3580);
FORCEADD UNIVERSAL_GND..1
(-8500 3325);
FORCEPROP 3 LASTPIN (-8500 3375) SIG_NAME GND\g
J 0
(-8490 3385);
DISPLAY 0.659574 (-8490 3385);
PAINT MONO (-8490 3385);
DISPLAY INVISIBLE (-8490 3385);
FORCEPROP 2 LAST CDS_LIB pure_quanta_power
J 0
(-8500 3325);
DISPLAY INVISIBLE (-8500 3325);
FORCEPROP 1 LAST HDL_POWER GND
J 1
(-8475 3250);
DISPLAY 0.872340 (-8475 3250);
PAINT GREEN (-8475 3250);
DISPLAY INVISIBLE (-8475 3250);
FORCEPROP 1 LAST PATH I8
J 0
(-8425 3325);
DISPLAY 0.872340 (-8425 3325);
PAINT AQUA (-8425 3325);
DISPLAY INVISIBLE (-8425 3325);
FORCEADD HOLE..1
(-3675 500);
FORCEPROP 1 LAST LOCATION H124
J 0
(-3800 735);
DISPLAY 0.723404 (-3800 735);
PAINT GREEN (-3800 735);
FORCEPROP 0 LAST $SEC 1
J 0
(-3800 825);
DISPLAY 0.680851 (-3800 825);
PAINT MONO (-3800 825);
DISPLAY INVISIBLE (-3800 825);
FORCEPROP 0 LAST CDS_SEC 1
J 0
(-3800 825);
DISPLAY 1.021277 (-3800 825);
DISPLAY INVISIBLE (-3800 825);
FORCEPROP 0 LASTPIN (-3875 525) $PN 1
J 2
(-3885 535);
DISPLAY 0.680851 (-3885 535);
PAINT MONO (-3885 535);
FORCEPROP 1 LAST MATERIAL EMPTY
J 0
(-3800 635);
DISPLAY 0.723404 (-3800 635);
PAINT GREEN (-3800 635);
FORCEPROP 2 LAST PACK_TYPE TH
J 0
(-3800 775);
DISPLAY 1.021277 (-3800 775);
FORCEPROP 2 LAST CDS_LIB pure_quanta
J 0
(-3675 500);
DISPLAY INVISIBLE (-3675 500);
FORCEPROP 1 LAST NEEDS_NO_SIZE TRUE
J 0
(-3675 500);
DISPLAY 0.468085 (-3675 500);
PAINT GREEN (-3675 500);
DISPLAY INVISIBLE (-3675 500);
FORCEPROP 1 LAST PATH I84
J 0
(-3625 630);
DISPLAY 0.723404 (-3625 630);
PAINT GREEN (-3625 630);
DISPLAY INVISIBLE (-3625 630);
FORCEPROP 1 LAST PART_NUMBER TMP-C_T2I_ALEX_1121_1
J 0
(-3800 680);
DISPLAY 0.723404 (-3800 680);
PAINT GREEN (-3800 680);
DISPLAY INVISIBLE (-3800 680);
FORCEADD HOLE..1
(-3625 925);
FORCEPROP 1 LAST LOCATION H125
J 0
(-3750 1160);
DISPLAY 0.723404 (-3750 1160);
PAINT GREEN (-3750 1160);
FORCEPROP 0 LAST $SEC 1
J 0
(-3750 1250);
DISPLAY 0.680851 (-3750 1250);
PAINT MONO (-3750 1250);
DISPLAY INVISIBLE (-3750 1250);
FORCEPROP 0 LAST CDS_SEC 1
J 0
(-3750 1250);
DISPLAY 1.021277 (-3750 1250);
DISPLAY INVISIBLE (-3750 1250);
FORCEPROP 0 LASTPIN (-3825 950) $PN 1
J 2
(-3835 960);
DISPLAY 0.680851 (-3835 960);
PAINT MONO (-3835 960);
FORCEPROP 2 LAST PACK_TYPE TH
J 0
(-3750 1200);
DISPLAY 1.021277 (-3750 1200);
FORCEPROP 1 LAST MATERIAL EMPTY
J 0
(-3750 1060);
DISPLAY 0.723404 (-3750 1060);
PAINT GREEN (-3750 1060);
FORCEPROP 1 LAST NEEDS_NO_SIZE TRUE
J 0
(-3625 925);
DISPLAY 0.468085 (-3625 925);
PAINT GREEN (-3625 925);
DISPLAY INVISIBLE (-3625 925);
FORCEPROP 2 LAST CDS_LIB pure_quanta
J 0
(-3625 925);
DISPLAY INVISIBLE (-3625 925);
FORCEPROP 1 LAST PATH I85
J 0
(-3575 1055);
DISPLAY 0.723404 (-3575 1055);
PAINT GREEN (-3575 1055);
DISPLAY INVISIBLE (-3575 1055);
FORCEPROP 1 LAST PART_NUMBER TMP-C_T2I_ALEX_1121_1
J 0
(-3750 1105);
DISPLAY 0.723404 (-3750 1105);
PAINT GREEN (-3750 1105);
DISPLAY INVISIBLE (-3750 1105);
FORCEADD UNIVERSAL_GND..1
(-5250 2700);
FORCEPROP 3 LASTPIN (-5250 2750) SIG_NAME GND\g
J 0
(-5240 2760);
DISPLAY 0.659574 (-5240 2760);
PAINT MONO (-5240 2760);
DISPLAY INVISIBLE (-5240 2760);
FORCEPROP 2 LAST CDS_LIB pure_quanta_power
J 0
(-5250 2700);
DISPLAY INVISIBLE (-5250 2700);
FORCEPROP 1 LAST HDL_POWER GND
J 1
(-5225 2625);
DISPLAY 0.872340 (-5225 2625);
PAINT GREEN (-5225 2625);
DISPLAY INVISIBLE (-5225 2625);
FORCEPROP 1 LAST PATH I86
J 0
(-5175 2700);
DISPLAY 0.872340 (-5175 2700);
PAINT AQUA (-5175 2700);
DISPLAY INVISIBLE (-5175 2700);
FORCEADD HOLE..1
(-5050 2775);
FORCEPROP 1 LAST LOCATION H11
J 0
(-5175 3010);
DISPLAY 0.489362 (-5175 3010);
PAINT SKYBLUE (-5175 3010);
FORCEPROP 0 LAST $SEC 1
J 0
(-5175 3075);
DISPLAY 0.680851 (-5175 3075);
PAINT MONO (-5175 3075);
DISPLAY INVISIBLE (-5175 3075);
FORCEPROP 0 LAST CDS_SEC 1
J 0
(-5175 3075);
DISPLAY 0.680851 (-5175 3075);
DISPLAY INVISIBLE (-5175 3075);
FORCEPROP 0 LASTPIN (-5250 2800) $PN 1
J 2
(-5260 2810);
DISPLAY 0.489362 (-5260 2810);
PAINT MONO (-5260 2810);
FORCEPROP 1 LAST MATERIAL EMPTY
J 0
(-5175 2910);
DISPLAY 0.489362 (-5175 2910);
PAINT RED (-5175 2910);
FORCEPROP 2 LAST PACK_TYPE TH
J 0
(-5175 3050);
DISPLAY 0.489362 (-5175 3050);
PAINT SKYBLUE (-5175 3050);
FORCEPROP 2 LAST CDS_LIB pure_quanta
J 0
(-5050 2775);
DISPLAY INVISIBLE (-5050 2775);
FORCEPROP 1 LAST NEEDS_NO_SIZE TRUE
J 0
(-5050 2775);
DISPLAY 0.468085 (-5050 2775);
PAINT GREEN (-5050 2775);
DISPLAY INVISIBLE (-5050 2775);
FORCEPROP 1 LAST PATH I87
J 0
(-5000 2905);
DISPLAY 0.723404 (-5000 2905);
PAINT GREEN (-5000 2905);
DISPLAY INVISIBLE (-5000 2905);
FORCEPROP 1 LAST PART_NUMBER HOLE1226
J 0
(-5175 2955);
DISPLAY 0.489362 (-5175 2955);
PAINT SKYBLUE (-5175 2955);
DISPLAY INVISIBLE (-5175 2955);
FORCEADD HOLE..1
(-4000 4325);
FORCEPROP 1 LAST LOCATION H74
J 0
(-4125 4560);
DISPLAY 0.723404 (-4125 4560);
PAINT GREEN (-4125 4560);
FORCEPROP 0 LAST $SEC 1
J 0
(-4125 4650);
DISPLAY 0.680851 (-4125 4650);
PAINT MONO (-4125 4650);
DISPLAY INVISIBLE (-4125 4650);
FORCEPROP 0 LAST CDS_SEC 1
J 0
(-4125 4650);
DISPLAY 1.021277 (-4125 4650);
DISPLAY INVISIBLE (-4125 4650);
FORCEPROP 0 LASTPIN (-4200 4350) $PN 1
J 2
(-4210 4360);
DISPLAY 0.680851 (-4210 4360);
PAINT MONO (-4210 4360);
FORCEPROP 1 LAST MATERIAL EMPTY
J 0
(-4125 4460);
DISPLAY 0.723404 (-4125 4460);
PAINT GREEN (-4125 4460);
FORCEPROP 2 LAST PACK_TYPE TH
J 0
(-4125 4600);
DISPLAY 1.021277 (-4125 4600);
FORCEPROP 2 LAST CDS_LIB pure_quanta
J 0
(-4000 4325);
DISPLAY INVISIBLE (-4000 4325);
FORCEPROP 1 LAST NEEDS_NO_SIZE TRUE
J 0
(-4000 4325);
DISPLAY 0.468085 (-4000 4325);
PAINT GREEN (-4000 4325);
DISPLAY INVISIBLE (-4000 4325);
FORCEPROP 1 LAST PATH I88
J 0
(-3950 4455);
DISPLAY 0.723404 (-3950 4455);
PAINT GREEN (-3950 4455);
DISPLAY INVISIBLE (-3950 4455);
FORCEPROP 1 LAST PART_NUMBER HOLE1247
J 0
(-4125 4505);
DISPLAY 0.723404 (-4125 4505);
PAINT GREEN (-4125 4505);
DISPLAY INVISIBLE (-4125 4505);
FORCEADD HOLE..1
(-3500 4325);
FORCEPROP 1 LAST LOCATION H75
J 0
(-3625 4560);
DISPLAY 0.723404 (-3625 4560);
PAINT GREEN (-3625 4560);
FORCEPROP 0 LAST $SEC 1
J 0
(-3625 4650);
DISPLAY 0.680851 (-3625 4650);
PAINT MONO (-3625 4650);
DISPLAY INVISIBLE (-3625 4650);
FORCEPROP 0 LAST CDS_SEC 1
J 0
(-3625 4650);
DISPLAY 1.021277 (-3625 4650);
DISPLAY INVISIBLE (-3625 4650);
FORCEPROP 0 LASTPIN (-3700 4350) $PN 1
J 2
(-3710 4360);
DISPLAY 0.680851 (-3710 4360);
PAINT MONO (-3710 4360);
FORCEPROP 1 LAST MATERIAL EMPTY
J 0
(-3625 4460);
DISPLAY 0.723404 (-3625 4460);
PAINT GREEN (-3625 4460);
FORCEPROP 2 LAST PACK_TYPE TH
J 0
(-3625 4600);
DISPLAY 1.021277 (-3625 4600);
FORCEPROP 2 LAST CDS_LIB pure_quanta
J 0
(-3500 4325);
DISPLAY INVISIBLE (-3500 4325);
FORCEPROP 1 LAST NEEDS_NO_SIZE TRUE
J 0
(-3500 4325);
DISPLAY 0.468085 (-3500 4325);
PAINT GREEN (-3500 4325);
DISPLAY INVISIBLE (-3500 4325);
FORCEPROP 1 LAST PATH I89
J 0
(-3450 4455);
DISPLAY 0.723404 (-3450 4455);
PAINT GREEN (-3450 4455);
DISPLAY INVISIBLE (-3450 4455);
FORCEPROP 1 LAST PART_NUMBER HOLE1247
J 0
(-3625 4505);
DISPLAY 0.723404 (-3625 4505);
PAINT GREEN (-3625 4505);
DISPLAY INVISIBLE (-3625 4505);
FORCEADD UNIVERSAL_GND..1
(-9000 4075);
FORCEPROP 3 LASTPIN (-9000 4125) SIG_NAME GND\g
J 0
(-8990 4135);
DISPLAY 0.659574 (-8990 4135);
PAINT MONO (-8990 4135);
DISPLAY INVISIBLE (-8990 4135);
FORCEPROP 2 LAST CDS_LIB pure_quanta_power
J 0
(-9000 4075);
DISPLAY INVISIBLE (-9000 4075);
FORCEPROP 1 LAST HDL_POWER GND
J 1
(-8975 4000);
DISPLAY 0.872340 (-8975 4000);
PAINT GREEN (-8975 4000);
DISPLAY INVISIBLE (-8975 4000);
FORCEPROP 1 LAST PATH I9
J 0
(-8925 4075);
DISPLAY 0.872340 (-8925 4075);
PAINT AQUA (-8925 4075);
DISPLAY INVISIBLE (-8925 4075);
FORCEADD UNIVERSAL_GND..1
(-4225 3125);
FORCEPROP 3 LASTPIN (-4225 3175) SIG_NAME GND\g
J 0
(-4215 3185);
DISPLAY 0.659574 (-4215 3185);
PAINT MONO (-4215 3185);
DISPLAY INVISIBLE (-4215 3185);
FORCEPROP 2 LAST CDS_LIB pure_quanta_power
J 0
(-4225 3125);
DISPLAY INVISIBLE (-4225 3125);
FORCEPROP 1 LAST HDL_POWER GND
J 1
(-4200 3050);
DISPLAY 0.872340 (-4200 3050);
PAINT GREEN (-4200 3050);
DISPLAY INVISIBLE (-4200 3050);
FORCEPROP 1 LAST PATH I90
J 0
(-4150 3125);
DISPLAY 0.872340 (-4150 3125);
PAINT AQUA (-4150 3125);
DISPLAY INVISIBLE (-4150 3125);
FORCEADD HOLE..1
(-3950 3275);
FORCEPROP 1 LAST LOCATION H31
J 0
(-4075 3510);
DISPLAY 0.723404 (-4075 3510);
PAINT GREEN (-4075 3510);
FORCEPROP 0 LAST $SEC 1
J 0
(-4075 3600);
DISPLAY 0.680851 (-4075 3600);
PAINT MONO (-4075 3600);
DISPLAY INVISIBLE (-4075 3600);
FORCEPROP 2 LAST CDS_SEC 1
J 0
(-4075 3600);
DISPLAY 1.021277 (-4075 3600);
DISPLAY INVISIBLE (-4075 3600);
FORCEPROP 0 LASTPIN (-4150 3300) $PN 1
J 2
(-4160 3310);
DISPLAY 0.680851 (-4160 3310);
PAINT MONO (-4160 3310);
FORCEPROP 2 LAST PACK_TYPE TH
J 0
(-4075 3550);
DISPLAY 1.021277 (-4075 3550);
FORCEPROP 1 LAST MATERIAL EMPTY
J 0
(-4075 3410);
DISPLAY 0.723404 (-4075 3410);
PAINT GREEN (-4075 3410);
FORCEPROP 1 LAST NEEDS_NO_SIZE TRUE
J 0
(-3950 3275);
DISPLAY 0.468085 (-3950 3275);
PAINT GREEN (-3950 3275);
DISPLAY INVISIBLE (-3950 3275);
FORCEPROP 2 LAST CDS_LIB pure_quanta
J 0
(-3950 3275);
DISPLAY INVISIBLE (-3950 3275);
FORCEPROP 1 LAST PATH I91
J 0
(-3900 3405);
DISPLAY 0.723404 (-3900 3405);
PAINT GREEN (-3900 3405);
DISPLAY INVISIBLE (-3900 3405);
FORCEPROP 1 LAST PART_NUMBER HOLE1248
J 0
(-4075 3455);
DISPLAY 0.723404 (-4075 3455);
PAINT GREEN (-4075 3455);
DISPLAY INVISIBLE (-4075 3455);
FORCEADD UNIVERSAL_GND..1
(-3725 3125);
FORCEPROP 3 LASTPIN (-3725 3175) SIG_NAME GND\g
J 0
(-3715 3185);
DISPLAY 0.659574 (-3715 3185);
PAINT MONO (-3715 3185);
DISPLAY INVISIBLE (-3715 3185);
FORCEPROP 2 LAST CDS_LIB pure_quanta_power
J 0
(-3725 3125);
DISPLAY INVISIBLE (-3725 3125);
FORCEPROP 1 LAST HDL_POWER GND
J 1
(-3700 3050);
DISPLAY 0.872340 (-3700 3050);
PAINT GREEN (-3700 3050);
DISPLAY INVISIBLE (-3700 3050);
FORCEPROP 1 LAST PATH I92
J 0
(-3650 3125);
DISPLAY 0.872340 (-3650 3125);
PAINT AQUA (-3650 3125);
DISPLAY INVISIBLE (-3650 3125);
FORCEADD HOLE..1
(-3450 3275);
FORCEPROP 1 LAST LOCATION H32
J 0
(-3575 3510);
DISPLAY 0.723404 (-3575 3510);
PAINT GREEN (-3575 3510);
FORCEPROP 0 LAST $SEC 1
J 0
(-3575 3600);
DISPLAY 0.680851 (-3575 3600);
PAINT MONO (-3575 3600);
DISPLAY INVISIBLE (-3575 3600);
FORCEPROP 2 LAST CDS_SEC 1
J 0
(-3575 3600);
DISPLAY 1.021277 (-3575 3600);
DISPLAY INVISIBLE (-3575 3600);
FORCEPROP 0 LASTPIN (-3650 3300) $PN 1
J 2
(-3660 3310);
DISPLAY 0.680851 (-3660 3310);
PAINT MONO (-3660 3310);
FORCEPROP 2 LAST PACK_TYPE TH
J 0
(-3575 3550);
DISPLAY 1.021277 (-3575 3550);
FORCEPROP 1 LAST MATERIAL EMPTY
J 0
(-3575 3410);
DISPLAY 0.723404 (-3575 3410);
PAINT GREEN (-3575 3410);
FORCEPROP 1 LAST NEEDS_NO_SIZE TRUE
J 0
(-3450 3275);
DISPLAY 0.468085 (-3450 3275);
PAINT GREEN (-3450 3275);
DISPLAY INVISIBLE (-3450 3275);
FORCEPROP 2 LAST CDS_LIB pure_quanta
J 0
(-3450 3275);
DISPLAY INVISIBLE (-3450 3275);
FORCEPROP 1 LAST PATH I93
J 0
(-3400 3405);
DISPLAY 0.723404 (-3400 3405);
PAINT GREEN (-3400 3405);
DISPLAY INVISIBLE (-3400 3405);
FORCEPROP 1 LAST PART_NUMBER HOLE1248
J 0
(-3575 3455);
DISPLAY 0.723404 (-3575 3455);
PAINT GREEN (-3575 3455);
DISPLAY INVISIBLE (-3575 3455);
FORCEADD HOLE..1
(-2850 900);
FORCEPROP 1 LAST LOCATION H127
J 0
(-2975 1135);
DISPLAY 0.723404 (-2975 1135);
PAINT GREEN (-2975 1135);
FORCEPROP 0 LAST $SEC 1
J 0
(-2975 1225);
DISPLAY 0.680851 (-2975 1225);
PAINT MONO (-2975 1225);
DISPLAY INVISIBLE (-2975 1225);
FORCEPROP 0 LAST CDS_SEC 1
J 0
(-2975 1225);
DISPLAY 1.021277 (-2975 1225);
DISPLAY INVISIBLE (-2975 1225);
FORCEPROP 0 LASTPIN (-3050 925) $PN 1
J 2
(-3060 935);
DISPLAY 0.680851 (-3060 935);
PAINT MONO (-3060 935);
FORCEPROP 2 LAST PACK_TYPE TH
J 0
(-2975 1175);
DISPLAY 1.021277 (-2975 1175);
FORCEPROP 1 LAST MATERIAL EMPTY
J 0
(-2975 1035);
DISPLAY 0.723404 (-2975 1035);
PAINT GREEN (-2975 1035);
FORCEPROP 1 LAST NEEDS_NO_SIZE TRUE
J 0
(-2850 900);
DISPLAY 0.468085 (-2850 900);
PAINT GREEN (-2850 900);
DISPLAY INVISIBLE (-2850 900);
FORCEPROP 2 LAST CDS_LIB pure_quanta
J 0
(-2850 900);
DISPLAY INVISIBLE (-2850 900);
FORCEPROP 1 LAST PATH I94
J 0
(-2800 1030);
DISPLAY 0.723404 (-2800 1030);
PAINT GREEN (-2800 1030);
DISPLAY INVISIBLE (-2800 1030);
FORCEPROP 1 LAST PART_NUMBER TMP-C_T2I_ALEX_1121_1
J 0
(-2975 1080);
DISPLAY 0.723404 (-2975 1080);
PAINT GREEN (-2975 1080);
DISPLAY INVISIBLE (-2975 1080);
FORCEADD QUANTA_TITLE_BLOCK_C..1
(0 0);
FORCEPROP 0 LAST CDS_CON_LAST_MODIFIED Thu Sep 14 16:12:43 2023
J 0
(-1885 15);
DISPLAY INVISIBLE (-1885 15);
FORCEPROP 1 LAST CUSTOM_TXT_CDS <CON_LAST_MODIFIED>
J 0
(-1885 15);
DISPLAY 0.978723 (-1885 15);
FORCEPROP 2 LAST CUSTOM_TXT_CDS <XR_PAGE_TITLE>
J 0
(-7890 5250);
DISPLAY 0.638298 (-7890 5250);
PAINT PINK (-7890 5250);
DISPLAY INVISIBLE (-7890 5250);
FORCEPROP 1 LAST CUSTOM_TXT_CDS <NAME_2>
J 0
(-3175 50);
FORCEPROP 1 LAST CUSTOM_TXT_CDS <NAME_1>
J 0
(-3175 175);
FORCEPROP 1 LAST CUSTOM_TXT_CDS <Q_NUMBER>
J 0
(-1403 103);
DISPLAY 1.212766 (-1403 103);
FORCEPROP 1 LAST CUSTOM_TXT_CDS <Q_PROJ>
J 0
(-2382 102);
DISPLAY 1.212766 (-2382 102);
FORCEPROP 1 LAST CUSTOM_TXT_CDS <Q_REV>
J 0
(-184 103);
DISPLAY 1.212766 (-184 103);
FORCEPROP 1 LAST CUSTOM_TXT_CDS <CON_PAGE_NUM> OF <CON_TOTAL_PAGES>
J 0
(-446 18);
DISPLAY 0.978723 (-446 18);
FORCEPROP 1 LAST Q_TITLE HOLE
J 0
(-9366 26);
DISPLAY 2.446809 (-9366 26);
PAINT GREEN (-9366 26);
FORCEPROP 2 LAST PAGE_BORDER TRUE
J 0
(-7890 5250);
DISPLAY 0.638298 (-7890 5250);
PAINT PINK (-7890 5250);
DISPLAY INVISIBLE (-7890 5250);
FORCEPROP 1 LAST CDS_LMAN_SYM_OUTLINE -9475,6775,100,-125
J 0
(0 0);
DISPLAY 0.468085 (0 0);
PAINT GREEN (0 0);
DISPLAY INVISIBLE (0 0);
FORCEPROP 2 LAST CDS_LIB pure_quanta
J 0
(0 0);
DISPLAY INVISIBLE (0 0);
FORCEPROP 2 LAST CDS_XR_PAGE_TITLE CR-230 : @T6G_MB_LIB.T6G(SCH_1):PAGE230
J 0
(-7890 5250);
DISPLAY 0.638298 (-7890 5250);
PAINT PINK (-7890 5250);
DISPLAY INVISIBLE (-7890 5250);
FORCEPROP 1 LAST Q_DEPT BU9
J 1
(-3763 49);
DISPLAY 1.957447 (-3763 49);
PAINT GREEN (-3763 49);
DISPLAY INVISIBLE (-3763 49);
FORCEPROP 1 LAST COMMENT_BODY TRUE
J 0
(12 -13);
DISPLAY 0.978723 (12 -13);
PAINT GREEN (12 -13);
DISPLAY INVISIBLE (12 -13);
WIRE 16 -1 (-1025 1425)(-1025 1375);
WIRE 16 -1 (-500 1400)(-500 1350);
WIRE 16 -1 (-9100 5900)(-9000 5900);
WIRE 16 -1 (-9100 5900)(-9100 5800);
WIRE 16 -1 (-9050 5350)(-9050 5275);
WIRE 16 -1 (-9050 5350)(-8975 5350);
WIRE 16 -1 (-8475 5925)(-8375 5925);
WIRE 16 -1 (-8475 5925)(-8475 5850);
WIRE 16 -1 (-8425 5350)(-8350 5350);
WIRE 16 -1 (-8425 5350)(-8425 5275);
WIRE 16 -1 (-7775 5925)(-7675 5925);
WIRE 16 -1 (-7775 5925)(-7775 5875);
WIRE 16 -1 (-7750 5375)(-7675 5375);
WIRE 16 -1 (-7750 5375)(-7750 5300);
WIRE 16 -1 (-7125 5925)(-7050 5925);
WIRE 16 -1 (-7125 5925)(-7125 5900);
WIRE 16 -1 (-7050 5350)(-7000 5350);
WIRE 16 -1 (-7050 5350)(-7050 5300);
WIRE 16 -1 (-6400 5375)(-6350 5375);
WIRE 16 -1 (-6400 5375)(-6400 5350);
WIRE 16 -1 (-6450 5900)(-6400 5900);
WIRE 16 -1 (-6450 5900)(-6450 5875);
WIRE 16 -1 (-5725 5950)(-5725 5900);
WIRE 16 -1 (-5725 5950)(-5675 5950);
WIRE 16 -1 (-5700 5325)(-5650 5325);
WIRE 16 -1 (-5700 5325)(-5700 5250);
WIRE 16 -1 (-5025 5950)(-4950 5950);
WIRE 16 -1 (-5025 5950)(-5025 5900);
WIRE 16 -1 (-5000 5325)(-4925 5325);
WIRE 16 -1 (-5000 5325)(-5000 5250);
WIRE 16 -1 (-4350 5950)(-4300 5950);
WIRE 16 -1 (-4350 5950)(-4350 5900);
WIRE 16 -1 (-4350 5325)(-4275 5325);
WIRE 16 -1 (-4350 5325)(-4350 5275);
WIRE 16 -1 (-3575 5975)(-3525 5975);
WIRE 16 -1 (-3575 5975)(-3575 5925);
WIRE 16 -1 (-3600 5350)(-3525 5350);
WIRE 16 -1 (-3600 5350)(-3600 5300);
WIRE 16 -1 (-2925 5975)(-2925 5925);
WIRE 16 -1 (-2925 5975)(-2875 5975);
WIRE 16 -1 (-2925 5325)(-2875 5325);
WIRE 16 -1 (-2925 5325)(-2925 5275);
WIRE 16 -1 (-2250 6025)(-2200 6025);
WIRE 16 -1 (-2250 6025)(-2250 5975);
WIRE 16 -1 (-725 4000)(-850 4000);
WIRE 16 -1 (-850 4000)(-850 3850);
WIRE 16 -1 (-8975 2200)(-8975 2150);
WIRE 16 -1 (-8375 2150)(-8375 2100);
WIRE 16 -1 (-7875 2125)(-7875 2075);
WIRE 16 -1 (-6225 2150)(-6225 2100);
WIRE 16 -1 (-6775 2150)(-6775 2100);
WIRE 16 -1 (-7325 2150)(-7325 2100);
WIRE 16 -1 (-8450 2825)(-8450 2775);
WIRE 16 -1 (-7900 2825)(-7900 2775);
WIRE 16 -1 (-9075 2850)(-9075 2800);
WIRE 16 -1 (-7350 2825)(-7350 2775);
WIRE 16 -1 (-6775 2825)(-6775 2775);
WIRE 16 -1 (-7950 3425)(-7950 3375);
WIRE 16 -1 (-7375 3425)(-7375 3375);
WIRE 16 -1 (-6875 3425)(-6875 3375);
WIRE 16 -1 (-6275 2825)(-6275 2775);
WIRE 16 -1 (-6325 3425)(-6325 3375);
WIRE 16 -1 (-5800 3425)(-5800 3375);
WIRE 16 -1 (-5225 3425)(-5225 3375);
WIRE 16 -1 (-5775 2800)(-5775 2750);
WIRE 16 -1 (-9050 3425)(-9050 3375);
WIRE 16 -1 (-8500 3425)(-8500 3375);
WIRE 16 -1 (-5250 2800)(-5250 2750);
WIRE 17 273 (-9075 2500)(-5725 2500);
WIRE 17 273 (-9075 2500)(-9075 1900);
WIRE 17 273 (-5725 2500)(-5725 1900);
WIRE 17 273 (-9075 1900)(-5725 1900);
WIRE 16 -1 (-8450 4250)(-8375 4250);
WIRE 16 -1 (-8450 4125)(-8450 4250);
WIRE 16 -1 (-7500 525)(-7325 525);
WIRE 16 -1 (-7500 800)(-7500 525);
WIRE 16 -1 (-7500 450)(-7500 525);
WIRE 16 -1 (-7325 525)(-7225 525);
WIRE 16 -1 (-7325 525)(-7325 600);
WIRE 16 -1 (-7225 525)(-7125 525);
WIRE 16 -1 (-7225 525)(-7225 600);
WIRE 16 -1 (-7500 900)(-7500 800);
WIRE 16 -1 (-7500 800)(-7425 800);
WIRE 16 -1 (-7500 900)(-7500 1075);
WIRE 16 -1 (-7500 900)(-7425 900);
WIRE 16 -1 (-7125 525)(-7125 600);
WIRE 16 -1 (-7125 525)(-6950 525);
WIRE 16 -1 (-6950 525)(-6950 800);
WIRE 16 -1 (-7500 1075)(-7225 1075);
WIRE 16 -1 (-7225 1075)(-6950 1075);
WIRE 16 -1 (-7225 1000)(-7225 1075);
WIRE 16 -1 (-6950 800)(-6950 900);
WIRE 16 -1 (-7025 800)(-6950 800);
WIRE 16 -1 (-6950 1075)(-6950 900);
WIRE 16 -1 (-7025 900)(-6950 900);
WIRE 16 -1 (-6750 550)(-6575 550);
WIRE 16 -1 (-6750 825)(-6750 550);
WIRE 16 -1 (-6750 475)(-6750 550);
WIRE 16 -1 (-6575 550)(-6475 550);
WIRE 16 -1 (-6575 550)(-6575 625);
WIRE 16 -1 (-6475 550)(-6375 550);
WIRE 16 -1 (-6475 550)(-6475 625);
WIRE 16 -1 (-6750 925)(-6750 825);
WIRE 16 -1 (-6750 825)(-6675 825);
WIRE 16 -1 (-6750 925)(-6750 1100);
WIRE 16 -1 (-6750 925)(-6675 925);
WIRE 16 -1 (-6375 550)(-6375 625);
WIRE 16 -1 (-6375 550)(-6200 550);
WIRE 16 -1 (-6200 550)(-6200 825);
WIRE 16 -1 (-6750 1100)(-6475 1100);
WIRE 16 -1 (-6475 1100)(-6200 1100);
WIRE 16 -1 (-6475 1025)(-6475 1100);
WIRE 16 -1 (-6200 825)(-6200 925);
WIRE 16 -1 (-6275 825)(-6200 825);
WIRE 16 -1 (-6200 1100)(-6200 925);
WIRE 16 -1 (-6275 925)(-6200 925);
WIRE 16 -1 (-9125 575)(-8950 575);
WIRE 16 -1 (-9125 850)(-9125 575);
WIRE 16 -1 (-9125 500)(-9125 575);
WIRE 16 -1 (-8950 575)(-8950 650);
WIRE 16 -1 (-8950 575)(-8850 575);
WIRE 16 -1 (-8850 575)(-8750 575);
WIRE 16 -1 (-8850 575)(-8850 650);
WIRE 16 -1 (-9125 850)(-9050 850);
WIRE 16 -1 (-9125 950)(-9125 850);
WIRE 16 -1 (-9125 950)(-9125 1125);
WIRE 16 -1 (-9125 950)(-9050 950);
WIRE 16 -1 (-8750 575)(-8575 575);
WIRE 16 -1 (-8750 575)(-8750 650);
WIRE 16 -1 (-8575 575)(-8575 850);
WIRE 16 -1 (-9125 1125)(-8850 1125);
WIRE 16 -1 (-8850 1125)(-8575 1125);
WIRE 16 -1 (-8850 1050)(-8850 1125);
WIRE 16 -1 (-8575 850)(-8575 950);
WIRE 16 -1 (-8650 850)(-8575 850);
WIRE 16 -1 (-8575 1125)(-8575 950);
WIRE 16 -1 (-8650 950)(-8575 950);
WIRE 16 -1 (-8350 600)(-8175 600);
WIRE 16 -1 (-8350 875)(-8350 600);
WIRE 16 -1 (-8350 525)(-8350 600);
WIRE 16 -1 (-8175 600)(-8175 675);
WIRE 16 -1 (-8175 600)(-8075 600);
WIRE 16 -1 (-8075 600)(-7975 600);
WIRE 16 -1 (-8075 600)(-8075 675);
WIRE 16 -1 (-8350 875)(-8275 875);
WIRE 16 -1 (-8350 975)(-8350 875);
WIRE 16 -1 (-8350 975)(-8350 1150);
WIRE 16 -1 (-8350 975)(-8275 975);
WIRE 16 -1 (-7975 600)(-7800 600);
WIRE 16 -1 (-7975 600)(-7975 675);
WIRE 16 -1 (-7800 600)(-7800 875);
WIRE 16 -1 (-8350 1150)(-8075 1150);
WIRE 16 -1 (-8075 1075)(-8075 1150);
WIRE 16 -1 (-8075 1150)(-7800 1150);
WIRE 16 -1 (-7800 875)(-7800 975);
WIRE 16 -1 (-7875 875)(-7800 875);
WIRE 16 -1 (-7800 1150)(-7800 975);
WIRE 16 -1 (-7875 975)(-7800 975);
WIRE 16 -1 (-5700 575)(-5525 575);
WIRE 16 -1 (-5700 850)(-5700 575);
WIRE 16 -1 (-5700 500)(-5700 575);
WIRE 16 -1 (-5525 575)(-5425 575);
WIRE 16 -1 (-5525 575)(-5525 650);
WIRE 16 -1 (-5425 575)(-5325 575);
WIRE 16 -1 (-5425 575)(-5425 650);
WIRE 16 -1 (-5700 850)(-5625 850);
WIRE 16 -1 (-5700 950)(-5700 850);
WIRE 16 -1 (-5700 950)(-5700 1125);
WIRE 16 -1 (-5700 950)(-5625 950);
WIRE 16 -1 (-5325 575)(-5325 650);
WIRE 16 -1 (-5325 575)(-5150 575);
WIRE 16 -1 (-5150 575)(-5150 850);
WIRE 16 -1 (-5700 1125)(-5425 1125);
WIRE 16 -1 (-5425 1125)(-5150 1125);
WIRE 16 -1 (-5425 1050)(-5425 1125);
WIRE 16 -1 (-5150 850)(-5150 950);
WIRE 16 -1 (-5225 850)(-5150 850);
WIRE 16 -1 (-5150 1125)(-5150 950);
WIRE 16 -1 (-5225 950)(-5150 950);
WIRE 16 -1 (-9000 4250)(-8925 4250);
WIRE 16 -1 (-9000 4125)(-9000 4250);
WIRE 16 -1 (-4225 3300)(-4150 3300);
WIRE 16 -1 (-4225 3175)(-4225 3300);
WIRE 16 -1 (-3725 3300)(-3650 3300);
WIRE 16 -1 (-3725 3175)(-3725 3300);
DOT 1 (-9125 575);
DOT 1 (-9125 850);
DOT 1 (-9125 950);
DOT 1 (-8950 575);
DOT 1 (-8850 575);
DOT 1 (-8750 575);
DOT 1 (-8575 850);
DOT 1 (-8350 600);
DOT 1 (-8350 875);
DOT 1 (-8175 600);
DOT 1 (-8075 600);
DOT 1 (-8850 1125);
DOT 1 (-8575 950);
DOT 1 (-8350 975);
DOT 1 (-8075 1150);
DOT 1 (-7800 975);
DOT 1 (-7500 525);
DOT 1 (-7500 900);
DOT 1 (-7325 525);
DOT 1 (-7225 525);
DOT 1 (-7125 525);
DOT 1 (-6950 900);
DOT 1 (-6950 800);
DOT 1 (-6750 550);
DOT 1 (-6575 550);
DOT 1 (-6750 925);
DOT 1 (-6750 825);
DOT 1 (-7225 1075);
DOT 1 (-6475 550);
DOT 1 (-6375 550);
DOT 1 (-6200 825);
DOT 1 (-6200 925);
DOT 1 (-6475 1100);
DOT 1 (-5325 575);
DOT 1 (-5700 575);
DOT 1 (-5525 575);
DOT 1 (-5700 950);
DOT 1 (-5700 850);
DOT 1 (-5150 850);
DOT 1 (-5150 950);
DOT 1 (-5425 1125);
DOT 1 (-5425 575);
DOT 1 (-7800 875);
DOT 1 (-7975 600);
DOT 1 (-7500 800);
FORCENOTE
ADD FOR RETIMER VR
(-9025 2550) 0;
DISPLAY LEFT (-9025 2550);
DISPLAY 1.021277 (-9025 2550);
FORCENOTE
GND_HOLE140 (HANDLE)
(-9000 1500) 0;
DISPLAY LEFT (-9000 1500);
DISPLAY 1.276596 (-9000 1500);
PAINT GREEN (-9000 1500);
FORCENOTE
HOLE300 (CPU HS HOLE)
(-3775 1425) 0;
DISPLAY LEFT (-3775 1425);
DISPLAY 1.276596 (-3775 1425);
PAINT GREEN (-3775 1425);
FORCENOTE
HOLE_D10N
(-3775 1550) 0;
DISPLAY LEFT (-3775 1550);
DISPLAY 1.595745 (-3775 1550);
PAINT SKYBLUE (-3775 1550);
FORCENOTE
RT HS HOLE WILL DEFINE IN DXF/EMN
(-4000 2350) 0;
DISPLAY LEFT (-4000 2350);
DISPLAY 1.021277 (-4000 2350);
FORCENOTE
RETIMER HS HOLE
(-4025 2450) 0;
DISPLAY LEFT (-4025 2450);
DISPLAY 1.276596 (-4025 2450);
PAINT GREEN (-4025 2450);
FORCENOTE
HOLE_C4-5D3-8B8I5-6_RO6-6_NPT_RB
(-4200 3775) 0;
DISPLAY LEFT (-4200 3775);
DISPLAY 1.595745 (-4200 3775);
PAINT SKYBLUE (-4200 3775);
FORCENOTE
HOLE1248 (M.2 LATCH HOLE)
(-4175 3650) 0;
DISPLAY LEFT (-4175 3650);
DISPLAY 1.276596 (-4175 3650);
PAINT GREEN (-4175 3650);
FORCENOTE
HSC MODULE CONN HOLE
(-1300 4450) 0;
DISPLAY LEFT (-1300 4450);
DISPLAY 1.276596 (-1300 4450);
PAINT GREEN (-1300 4450);
FORCENOTE
HOLE_OB6-4X8OBD3-2X4-8B6-4X8N_RO6X7-6_NPM
(-4175 4875) 0;
DISPLAY LEFT (-4175 4875);
DISPLAY 1.595745 (-4175 4875);
PAINT SKYBLUE (-4175 4875);
FORCENOTE
HOLE1187 (E1S SCREW HOLE)
(-9000 4625) 0;
DISPLAY LEFT (-9000 4625);
DISPLAY 1.276596 (-9000 4625);
PAINT GREEN (-9000 4625);
FORCENOTE
VR HS HOLE
(-9025 3800) 0;
DISPLAY LEFT (-9025 3800);
DISPLAY 1.276596 (-9025 3800);
PAINT GREEN (-9025 3800);
FORCENOTE
P3V3_AUX HS HOLE
(-1125 1725) 0;
DISPLAY LEFT (-1125 1725);
DISPLAY 1.276596 (-1125 1725);
PAINT GREEN (-1125 1725);
FORCENOTE
GND_HOLE514(STD)
(-5600 1400) 0;
DISPLAY LEFT (-5600 1400);
DISPLAY 1.276596 (-5600 1400);
PAINT GREEN (-5600 1400);
FORCENOTE
HOLE_R4-2X5D2B4_IX0-1T_NPM_RB
(-9025 4775) 0;
DISPLAY LEFT (-9025 4775);
DISPLAY 1.595745 (-9025 4775);
PAINT SKYBLUE (-9025 4775);
FORCENOTE
HOLE 596
(-9125 6375) 0;
DISPLAY LEFT (-9125 6375);
DISPLAY 1.276596 (-9125 6375);
PAINT GREEN (-9125 6375);
FORCENOTE
HOLE372(GUIDE PIN)
(-1350 6450) 0;
DISPLAY LEFT (-1350 6450);
DISPLAY 1.276596 (-1350 6450);
PAINT GREEN (-1350 6450);
FORCENOTE
HOLE_DUMMY50
(-6425 4800) 0;
DISPLAY LEFT (-6425 4800);
DISPLAY 1.595745 (-6425 4800);
PAINT SKYBLUE (-6425 4800);
FORCENOTE
TOOLING HOLE
(-6425 4675) 0;
DISPLAY LEFT (-6425 4675);
DISPLAY 1.276596 (-6425 4675);
PAINT WHITE (-6425 4675);
FORCENOTE
HOLE1247(M.2)
(-4175 4750) 0;
DISPLAY LEFT (-4175 4750);
DISPLAY 1.276596 (-4175 4750);
PAINT GREEN (-4175 4750);
FORCENOTE
HOLE_C10D5-6B10_NPB
(-9125 6475) 0;
DISPLAY LEFT (-9125 6475);
DISPLAY 1.595745 (-9125 6475);
PAINT SKYBLUE (-9125 6475);
FORCENOTE
GND_C8D4B8
(-7425 1375) 0;
DISPLAY LEFT (-7425 1375);
DISPLAY 1.276596 (-7425 1375);
PAINT GREEN (-7425 1375);
QUIT
